G04 ================== begin FILE IDENTIFICATION RECORD ==================*
G04 Layout Name:  E:/<user>/9332_F0TG_MB_C/brd/0417/9332_F0TG_MB_C_V02_0417_0820.brd*
G04 Film Name:    panel*
G04 File Format:  Gerber RS274X*
G04 File Origin:  Cadence Allegro 17.2-S081*
G04 Origin Date:  Wed Apr 19 14:50:07 2023*
G04 *
G04 Layer:  DRAWING FORMAT/TITLE_BLOCK_A*
G04 Layer:  MANUFACTURING/PHOTOPLOT_OUTLINE*
G04 Layer:  DRAWING FORMAT/TITLE_BLOCK*
G04 Layer:  DRAWING FORMAT/TITLE_DATA_PANEL*
G04 Layer:  BOARD GEOMETRY/ASSEMBLY_NOTES*
G04 *
G04 Offset:    (0.00 0.00)*
G04 Mirror:    No*
G04 Mode:      Positive*
G04 Rotation:  0*
G04 FullContactRelief:  No*
G04 UndefLineWidth:     6.00*
G04 ================== end FILE IDENTIFICATION RECORD ====================*
%FSLAX25Y25*MOIN*%
%IR0*IPPOS*OFA0.00000B0.00000*MIA0B0*SFA1.00000B1.00000*%
%ADD10C,.04*%
%ADD11C,.006*%
G75*
%LPD*%
G75*
G36*
G01X49212Y-29134D02*
G02I-1968J0D01*
G37*
G36*
G01X2036614Y1803261D02*
G02I-1969J0D01*
G37*
G36*
G01X2237007Y83771D02*
G02I-1969J0D01*
G37*
G54D10*
G01X2075874Y1277688D02*
X2076654Y1278858D01*
X2077174Y1280223D01*
Y1281783D01*
X2076394Y1283538D01*
X2075094Y1284903D01*
X2073534Y1285878D01*
X2070934Y1286658D01*
X2068594Y1286853D01*
X2066254Y1286463D01*
X2064694Y1285878D01*
X2063134Y1284708D01*
X2062094Y1283343D01*
X2061574Y1281978D01*
Y1280613D01*
X2062094Y1279248D01*
X2062874Y1278078D01*
X2063914Y1277103D01*
G01X2069894Y1262518D02*
X2070674Y1261738D01*
X2071974Y1261153D01*
X2073794Y1260763D01*
X2075354Y1261153D01*
X2076394Y1261933D01*
X2077174Y1263298D01*
Y1268563D01*
X2061574D01*
Y1262128D01*
X2062614Y1260763D01*
X2064174Y1259983D01*
X2065994Y1259593D01*
X2067814Y1259983D01*
X2069374Y1261153D01*
X2069894Y1262518D01*
Y1268563D01*
G01X2074174Y1756818D02*
Y1752138D01*
G01Y1754478D02*
X2058574D01*
G01Y1756818D02*
Y1752138D01*
G01X2060654Y1740673D02*
X2059354Y1739113D01*
X2058574Y1737358D01*
Y1735798D01*
X2059354Y1734238D01*
X2060654Y1733068D01*
X2062474Y1732483D01*
X2064294Y1732873D01*
X2065854Y1733848D01*
X2066894Y1735603D01*
X2067414Y1737943D01*
X2068454Y1739308D01*
X2070274Y1739893D01*
X2072094Y1739503D01*
X2073394Y1738528D01*
X2074174Y1737163D01*
Y1735798D01*
X2073654Y1734433D01*
X2072354Y1733263D01*
G01X2074174Y1718678D02*
X2058574D01*
G01X2074174Y1723163D02*
Y1714193D01*
G01X2066374Y1681708D02*
Y1677808D01*
X2061694D01*
X2060134Y1678978D01*
X2059094Y1680343D01*
X2058574Y1682293D01*
X2059094Y1684243D01*
X2060134Y1685608D01*
X2061694Y1686778D01*
X2063514Y1687558D01*
X2065594Y1687948D01*
X2067414D01*
X2068974Y1687558D01*
X2070794Y1686778D01*
X2072354Y1685608D01*
X2073394Y1684438D01*
X2074174Y1682878D01*
Y1681513D01*
X2073654Y1679953D01*
X2072614Y1678783D01*
G01X2058574Y1661078D02*
Y1668878D01*
X2074174D01*
Y1661078D01*
G01X2066634Y1664198D02*
Y1668878D01*
G01X2058574Y1650978D02*
X2074174D01*
Y1646103D01*
X2073394Y1644543D01*
X2072354Y1643568D01*
X2070274Y1643178D01*
X2068194Y1643568D01*
X2066894Y1644738D01*
X2066114Y1646103D01*
Y1650978D01*
G01Y1646103D02*
X2058574Y1643178D01*
G01X2066894Y1627618D02*
X2067674Y1626838D01*
X2068974Y1626253D01*
X2070794Y1625863D01*
X2072354Y1626253D01*
X2073394Y1627033D01*
X2074174Y1628398D01*
Y1633663D01*
X2058574D01*
Y1627228D01*
X2059614Y1625863D01*
X2061174Y1625083D01*
X2062994Y1624693D01*
X2064814Y1625083D01*
X2066374Y1626253D01*
X2066894Y1627618D01*
Y1633663D01*
G01X2058574Y1607378D02*
Y1615178D01*
X2074174D01*
Y1607378D01*
G01X2066634Y1610498D02*
Y1615178D01*
G01X2058574Y1597278D02*
X2074174D01*
Y1592403D01*
X2073394Y1590843D01*
X2072354Y1589868D01*
X2070274Y1589478D01*
X2068194Y1589868D01*
X2066894Y1591038D01*
X2066114Y1592403D01*
Y1597278D01*
G01Y1592403D02*
X2058574Y1589478D01*
G01X2053374Y1576453D02*
X2055974Y1578403D01*
X2058574Y1579378D01*
X2068974D01*
X2071574Y1578403D01*
X2074174Y1576453D01*
G01X2067674Y1554458D02*
X2068714Y1555823D01*
X2068974Y1556993D01*
X2068454Y1558553D01*
X2067414Y1559723D01*
X2065594Y1560503D01*
X2063774Y1560698D01*
X2061954Y1560503D01*
X2060394Y1559723D01*
X2059094Y1558553D01*
X2058574Y1556993D01*
X2059094Y1555628D01*
X2060134Y1554458D01*
G01X2058574Y1543188D02*
X2074174D01*
G01X2066374D02*
X2067934Y1542213D01*
X2068714Y1541043D01*
X2068974Y1539873D01*
X2068454Y1538118D01*
X2067414Y1536948D01*
X2065594Y1536168D01*
X2063514D01*
X2061434Y1536558D01*
X2059874Y1537338D01*
X2058834Y1538703D01*
X2058574Y1539873D01*
X2058834Y1541043D01*
X2059614Y1542213D01*
X2060914Y1543188D01*
G01X2068974Y1524703D02*
X2058574Y1518853D01*
G01X2068974D02*
X2058574Y1524703D01*
G01Y1503878D02*
X2074174D01*
X2071054Y1506218D01*
G01X2058574D02*
Y1501538D01*
G01Y1485978D02*
X2058834Y1484613D01*
X2059614Y1483053D01*
X2060914Y1482078D01*
X2062734Y1481688D01*
X2064554Y1482078D01*
X2066114Y1483248D01*
X2066894Y1485003D01*
Y1486953D01*
X2067414Y1488123D01*
X2068714Y1489098D01*
X2070534Y1489488D01*
X2072354Y1488903D01*
X2073654Y1487538D01*
X2074174Y1485978D01*
X2073654Y1484418D01*
X2072354Y1483053D01*
X2070534Y1482468D01*
X2068714Y1482858D01*
X2067414Y1483833D01*
X2066894Y1485003D01*
Y1486953D01*
X2066114Y1488708D01*
X2064554Y1489878D01*
X2062734Y1490268D01*
X2060914Y1489878D01*
X2059614Y1488903D01*
X2058834Y1487343D01*
X2058574Y1485978D01*
G01X2074174Y1468078D02*
X2073654Y1469638D01*
X2072354Y1470808D01*
X2070794Y1471588D01*
X2068714Y1472173D01*
X2066374Y1472368D01*
X2064034Y1472173D01*
X2061954Y1471588D01*
X2060394Y1470808D01*
X2059094Y1469638D01*
X2058574Y1468078D01*
X2059094Y1466518D01*
X2060394Y1465348D01*
X2061954Y1464568D01*
X2064034Y1463983D01*
X2066374Y1463788D01*
X2068714Y1463983D01*
X2070794Y1464568D01*
X2072354Y1465348D01*
X2073654Y1466518D01*
X2074174Y1468078D01*
G01X2058574Y1447838D02*
X2074174D01*
X2062994Y1455053D01*
Y1445303D01*
G01X2060914Y1436568D02*
X2059614Y1435398D01*
X2058834Y1434033D01*
X2058574Y1432278D01*
X2059094Y1430523D01*
X2060134Y1429158D01*
X2061954Y1428183D01*
X2064034Y1427988D01*
X2066114Y1428378D01*
X2067414Y1429353D01*
X2068454Y1430718D01*
X2068714Y1432083D01*
X2068454Y1433448D01*
X2067414Y1435203D01*
X2074174Y1434618D01*
Y1429353D01*
G01X2058574Y1410868D02*
X2068974D01*
G01X2067154D02*
X2068194Y1411648D01*
X2068714Y1412818D01*
X2068974Y1414183D01*
X2068454Y1415548D01*
X2067414Y1416718D01*
X2065854Y1417498D01*
X2063774Y1417888D01*
X2061694Y1417498D01*
X2060134Y1416718D01*
X2059094Y1415548D01*
X2058574Y1414183D01*
X2058834Y1412818D01*
X2059614Y1411648D01*
X2060654Y1410868D01*
G01X2053374Y1395503D02*
X2055974Y1393553D01*
X2058574Y1392578D01*
X2068974D01*
X2071574Y1393553D01*
X2074174Y1395503D01*
G54D11*
G01X-476840Y-884638D02*
Y2768362D01*
X5911000D01*
Y-884638D01*
X-476840D01*
G01X-9843Y1822946D02*
X-80079D01*
G01X-2990Y1783576D02*
X-39390D01*
G01X-12281Y-144553D02*
X-19777Y-144312D01*
X-19702Y-141980D01*
X-19303Y-141246D01*
X-18789Y-140795D01*
X-17783Y-140641D01*
X-16790Y-140860D01*
X-16183Y-141440D01*
X-15829Y-142105D01*
X-15904Y-144437D01*
G01X-15829Y-142105D02*
X-12161Y-140822D01*
G01X-18284Y-136763D02*
X-19015Y-136179D01*
X-19369Y-135514D01*
X-19470Y-134764D01*
X-19190Y-133839D01*
X-18545Y-133206D01*
X-17789Y-133044D01*
X-17042Y-133161D01*
X-16430Y-133554D01*
X-15240Y-135460D01*
X-14393Y-136328D01*
X-13161Y-136928D01*
X-12043Y-137150D01*
X-11917Y-133232D01*
G01X-11829Y-130494D02*
X-16826Y-130333D01*
G01X-15452Y-130378D02*
X-16068Y-130078D01*
X-16552Y-129595D01*
X-16781Y-128934D01*
X-16510Y-128289D01*
X-15996Y-127839D01*
X-15362Y-127579D01*
X-11739Y-127696D01*
G01X-15362Y-127579D02*
X-15978Y-127279D01*
X-16463Y-126797D01*
X-16691Y-126136D01*
X-16421Y-125491D01*
X-15906Y-125040D01*
X-15147Y-124784D01*
X-11649Y-124897D01*
G01X-11588Y-122998D02*
X-16585Y-122837D01*
G01X-15211Y-122882D02*
X-15827Y-122582D01*
X-16311Y-122099D01*
X-16540Y-121438D01*
X-16269Y-120793D01*
X-15755Y-120343D01*
X-15121Y-120083D01*
X-11498Y-120200D01*
G01X-15121Y-120083D02*
X-15737Y-119783D01*
X-16222Y-119301D01*
X-16450Y-118640D01*
X-16180Y-117995D01*
X-15665Y-117544D01*
X-14906Y-117288D01*
X-11408Y-117401D01*
G01X8000Y-625138D02*
Y-630138D01*
G01X6543Y-625138D02*
X9457D01*
G01X14367Y-630138D02*
X11833D01*
Y-625138D01*
X14367D01*
G01X13353Y-627555D02*
X11833D01*
G01X16933Y-625138D02*
Y-630138D01*
X19467D01*
G01X23300Y-630305D02*
X23173Y-630221D01*
Y-630055D01*
X23300Y-629971D01*
X23427Y-630055D01*
Y-630221D01*
X23300Y-630305D01*
G01Y-628055D02*
X23173Y-627971D01*
Y-627805D01*
X23300Y-627721D01*
X23427Y-627805D01*
Y-627971D01*
X23300Y-628055D01*
G01X28083Y-631805D02*
X27450Y-630971D01*
X27133Y-630138D01*
Y-626805D01*
X27450Y-625971D01*
X28083Y-625138D01*
G01X33500D02*
X32993Y-625305D01*
X32613Y-625721D01*
X32360Y-626221D01*
X32170Y-626888D01*
X32107Y-627638D01*
X32170Y-628388D01*
X32360Y-629055D01*
X32613Y-629555D01*
X32993Y-629971D01*
X33500Y-630138D01*
X34007Y-629971D01*
X34387Y-629555D01*
X34640Y-629055D01*
X34830Y-628388D01*
X34893Y-627638D01*
X34830Y-626888D01*
X34640Y-626221D01*
X34387Y-625721D01*
X34007Y-625305D01*
X33500Y-625138D01*
G01X37207Y-629138D02*
X37587Y-629721D01*
X38093Y-630055D01*
X38663Y-630138D01*
X39170Y-630055D01*
X39677Y-629638D01*
X39993Y-629138D01*
X40057Y-628638D01*
X39930Y-628055D01*
X39487Y-627638D01*
X39043Y-627471D01*
X38473D01*
G01X39043D02*
X39423Y-627221D01*
X39740Y-626805D01*
X39867Y-626305D01*
X39740Y-625805D01*
X39423Y-625388D01*
X38853Y-625138D01*
X38283Y-625221D01*
X37713Y-625555D01*
G01X44017Y-631805D02*
X44650Y-630971D01*
X44967Y-630138D01*
Y-626805D01*
X44650Y-625971D01*
X44017Y-625138D01*
G01X47407Y-629138D02*
X47787Y-629721D01*
X48293Y-630055D01*
X48863Y-630138D01*
X49370Y-630055D01*
X49877Y-629638D01*
X50193Y-629138D01*
X50257Y-628638D01*
X50130Y-628055D01*
X49687Y-627638D01*
X49243Y-627471D01*
X48673D01*
G01X49243D02*
X49623Y-627221D01*
X49940Y-626805D01*
X50067Y-626305D01*
X49940Y-625805D01*
X49623Y-625388D01*
X49053Y-625138D01*
X48483Y-625221D01*
X47913Y-625555D01*
G01X52697Y-625971D02*
X53077Y-625471D01*
X53520Y-625221D01*
X54027Y-625138D01*
X54660Y-625305D01*
X55103Y-625721D01*
X55230Y-626221D01*
X55167Y-626721D01*
X54913Y-627138D01*
X53647Y-627971D01*
X53077Y-628555D01*
X52697Y-629388D01*
X52570Y-630138D01*
X55230D01*
G01X58873D02*
X59000Y-629055D01*
X59190Y-628138D01*
X59443Y-627305D01*
X59760Y-626388D01*
X60267Y-625138D01*
X57733D01*
G01X63277Y-628471D02*
X64923D01*
G01X67997Y-625971D02*
X68377Y-625471D01*
X68820Y-625221D01*
X69327Y-625138D01*
X69960Y-625305D01*
X70403Y-625721D01*
X70530Y-626221D01*
X70467Y-626721D01*
X70213Y-627138D01*
X68947Y-627971D01*
X68377Y-628555D01*
X67997Y-629388D01*
X67870Y-630138D01*
X70530D01*
G01X72907Y-629138D02*
X73287Y-629721D01*
X73793Y-630055D01*
X74363Y-630138D01*
X74870Y-630055D01*
X75377Y-629638D01*
X75693Y-629138D01*
X75757Y-628638D01*
X75630Y-628055D01*
X75187Y-627638D01*
X74743Y-627471D01*
X74173D01*
G01X74743D02*
X75123Y-627221D01*
X75440Y-626805D01*
X75567Y-626305D01*
X75440Y-625805D01*
X75123Y-625388D01*
X74553Y-625138D01*
X73983Y-625221D01*
X73413Y-625555D01*
G01X80160Y-630138D02*
Y-625138D01*
X77817Y-628721D01*
X80983D01*
G01X83107Y-629388D02*
X83487Y-629805D01*
X83930Y-630055D01*
X84500Y-630138D01*
X85070Y-629971D01*
X85513Y-629638D01*
X85830Y-629055D01*
X85893Y-628388D01*
X85767Y-627721D01*
X85450Y-627305D01*
X85007Y-626971D01*
X84563Y-626888D01*
X84120Y-626971D01*
X83550Y-627305D01*
X83740Y-625138D01*
X85450D01*
G01X93497Y-630138D02*
Y-625138D01*
X95903D01*
G01X95017Y-627555D02*
X93497D01*
G01X98217Y-630138D02*
X99800Y-625138D01*
X101383Y-630138D01*
G01X100813Y-628388D02*
X98787D01*
G01X103570Y-630138D02*
X106230Y-625138D01*
G01X103570D02*
X106230Y-630138D01*
G01X110000Y-630305D02*
X109873Y-630221D01*
Y-630055D01*
X110000Y-629971D01*
X110127Y-630055D01*
Y-630221D01*
X110000Y-630305D01*
G01Y-628055D02*
X109873Y-627971D01*
Y-627805D01*
X110000Y-627721D01*
X110127Y-627805D01*
Y-627971D01*
X110000Y-628055D01*
G01X114783Y-631805D02*
X114150Y-630971D01*
X113833Y-630138D01*
Y-626805D01*
X114150Y-625971D01*
X114783Y-625138D01*
G01X120200D02*
X119693Y-625305D01*
X119313Y-625721D01*
X119060Y-626221D01*
X118870Y-626888D01*
X118807Y-627638D01*
X118870Y-628388D01*
X119060Y-629055D01*
X119313Y-629555D01*
X119693Y-629971D01*
X120200Y-630138D01*
X120707Y-629971D01*
X121087Y-629555D01*
X121340Y-629055D01*
X121530Y-628388D01*
X121593Y-627638D01*
X121530Y-626888D01*
X121340Y-626221D01*
X121087Y-625721D01*
X120707Y-625305D01*
X120200Y-625138D01*
G01X123907Y-629138D02*
X124287Y-629721D01*
X124793Y-630055D01*
X125363Y-630138D01*
X125870Y-630055D01*
X126377Y-629638D01*
X126693Y-629138D01*
X126757Y-628638D01*
X126630Y-628055D01*
X126187Y-627638D01*
X125743Y-627471D01*
X125173D01*
G01X125743D02*
X126123Y-627221D01*
X126440Y-626805D01*
X126567Y-626305D01*
X126440Y-625805D01*
X126123Y-625388D01*
X125553Y-625138D01*
X124983Y-625221D01*
X124413Y-625555D01*
G01X130717Y-631805D02*
X131350Y-630971D01*
X131667Y-630138D01*
Y-626805D01*
X131350Y-625971D01*
X130717Y-625138D01*
G01X134107Y-629138D02*
X134487Y-629721D01*
X134993Y-630055D01*
X135563Y-630138D01*
X136070Y-630055D01*
X136577Y-629638D01*
X136893Y-629138D01*
X136957Y-628638D01*
X136830Y-628055D01*
X136387Y-627638D01*
X135943Y-627471D01*
X135373D01*
G01X135943D02*
X136323Y-627221D01*
X136640Y-626805D01*
X136767Y-626305D01*
X136640Y-625805D01*
X136323Y-625388D01*
X135753Y-625138D01*
X135183Y-625221D01*
X134613Y-625555D01*
G01X139523Y-629555D02*
X139967Y-629971D01*
X140473Y-630138D01*
X140980Y-629971D01*
X141423Y-629471D01*
X141740Y-628721D01*
X141867Y-627971D01*
Y-627055D01*
X141740Y-626305D01*
X141423Y-625638D01*
X141043Y-625305D01*
X140600Y-625138D01*
X140093Y-625305D01*
X139713Y-625638D01*
X139460Y-626138D01*
X139333Y-626805D01*
X139460Y-627388D01*
X139777Y-627971D01*
X140157Y-628305D01*
X140600Y-628388D01*
X141107Y-628221D01*
X141487Y-627805D01*
X141867Y-627055D01*
G01X145573Y-630138D02*
X145700Y-629055D01*
X145890Y-628138D01*
X146143Y-627305D01*
X146460Y-626388D01*
X146967Y-625138D01*
X144433D01*
G01X149977Y-628471D02*
X151623D01*
G01X154507Y-629138D02*
X154887Y-629721D01*
X155393Y-630055D01*
X155963Y-630138D01*
X156470Y-630055D01*
X156977Y-629638D01*
X157293Y-629138D01*
X157357Y-628638D01*
X157230Y-628055D01*
X156787Y-627638D01*
X156343Y-627471D01*
X155773D01*
G01X156343D02*
X156723Y-627221D01*
X157040Y-626805D01*
X157167Y-626305D01*
X157040Y-625805D01*
X156723Y-625388D01*
X156153Y-625138D01*
X155583Y-625221D01*
X155013Y-625555D01*
G01X159797Y-628055D02*
X160240Y-627471D01*
X160620Y-627138D01*
X161127Y-626971D01*
X161570Y-627138D01*
X161887Y-627471D01*
X162140Y-627971D01*
X162203Y-628555D01*
X162140Y-629055D01*
X161887Y-629555D01*
X161507Y-629971D01*
X161063Y-630138D01*
X160557Y-629971D01*
X160113Y-629471D01*
X159860Y-628721D01*
X159797Y-627888D01*
X159923Y-626805D01*
X160113Y-626221D01*
X160430Y-625638D01*
X160873Y-625221D01*
X161317Y-625138D01*
X161760Y-625305D01*
X162077Y-625721D01*
G01X166100Y-630138D02*
Y-625138D01*
X165340Y-626138D01*
G01Y-630138D02*
X166860D01*
G01X171960D02*
Y-625138D01*
X169617Y-628721D01*
X172783D01*
G01X-4000Y-560138D02*
Y-635138D01*
X496000D01*
Y-560138D01*
X-4000D01*
G01X3643Y-47586D02*
X163Y-155842D01*
G01X5596Y-63405D02*
X3643Y-47586D01*
X677Y-63247D01*
X5596Y-63405D01*
G01X887008Y46378D02*
G02X879134Y38504I-7874J0D01*
G01X782291D01*
G03X774417Y30630I0J-7874D01*
G01Y19212D01*
G02X766543Y11338I-7874J0D01*
G01X496465D01*
G02X488591Y19212I0J7874D01*
G01Y30630D01*
G03X480717Y38504I-7874J0D01*
G01X337409D01*
G03X329535Y30630I0J-7874D01*
G01Y-1575D01*
G02X321661Y-9449I-7874J0D01*
G01X51583D01*
G02X43709Y-1575I0J7874D01*
G01Y30630D01*
G03X35835Y38504I-7874J0D01*
G01X7874D01*
G03X0Y30630I0J-7874D01*
G01Y-40945D01*
G03X7874Y-48819I7874J0D01*
G01X1849606D01*
G03X1857480Y-40945I0J7874D01*
G01X61000Y-48819D02*
X7874D01*
G02X0Y-40945I0J7874D01*
G01D02*
Y-25197D01*
G01X2306Y311361D02*
G03X0Y305793I5568J-5568D01*
G01Y54252D01*
G01X2306Y311361D02*
G03X0Y305793I5568J-5568D01*
G01Y54252D01*
G03X7874Y46378I7874J0D01*
G01X2306Y311361D02*
G03X0Y305793I5568J-5568D01*
G01Y54252D01*
G03X7874Y46378I7874J0D01*
G01X43709D01*
G01X2306Y311361D02*
G03X0Y305793I5568J-5568D01*
G01Y54252D01*
G03X7874Y46378I7874J0D01*
G01X43709D01*
G02X51583Y38504I0J-7874D01*
G01X2306Y311361D02*
G03X0Y305793I5568J-5568D01*
G01Y54252D01*
G03X7874Y46378I7874J0D01*
G01X43709D01*
G02X51583Y38504I0J-7874D01*
G01Y20397D01*
G01X2306Y311361D02*
G03X0Y305793I5568J-5568D01*
G01Y54252D01*
G03X7874Y46378I7874J0D01*
G01X43709D01*
G02X51583Y38504I0J-7874D01*
G01Y20397D01*
G01X2306Y311361D02*
G03X0Y305793I5568J-5568D01*
G01Y54252D01*
G03X7874Y46378I7874J0D01*
G01X43709D01*
G02X51583Y38504I0J-7874D01*
G01Y20397D01*
G01X2306Y311361D02*
G03X0Y305793I5568J-5568D01*
G01Y54252D01*
G03X7874Y46378I7874J0D01*
G01X43709D01*
G02X51583Y38504I0J-7874D01*
G01Y20397D01*
G01X2306Y311361D02*
G03X0Y305793I5568J-5568D01*
G01Y54252D01*
G03X7874Y46378I7874J0D01*
G01X43709D01*
G02X51583Y38504I0J-7874D01*
G01Y20397D01*
G01X2306Y311361D02*
G03X0Y305793I5568J-5568D01*
G01Y54252D01*
G03X7874Y46378I7874J0D01*
G01X43709D01*
G02X51583Y38504I0J-7874D01*
G01Y20397D01*
G01X2306Y311361D02*
G03X0Y305793I5568J-5568D01*
G01Y54252D01*
G03X7874Y46378I7874J0D01*
G01X43709D01*
G02X51583Y38504I0J-7874D01*
G01Y20397D01*
G01X2306Y311361D02*
G03X0Y305793I5568J-5568D01*
G01Y54252D01*
G03X7874Y46378I7874J0D01*
G01X43709D01*
G02X51583Y38504I0J-7874D01*
G01Y20397D01*
G01X2306Y311361D02*
G03X0Y305793I5568J-5568D01*
G01Y54252D01*
G03X7874Y46378I7874J0D01*
G01X43709D01*
G02X51583Y38504I0J-7874D01*
G01Y20397D01*
G01X2306Y311361D02*
G03X0Y305793I5568J-5568D01*
G01Y54252D01*
G03X7874Y46378I7874J0D01*
G01X43709D01*
G02X51583Y38504I0J-7874D01*
G01Y20397D01*
G01X2306Y311361D02*
G03X0Y305793I5568J-5568D01*
G01Y54252D01*
G03X7874Y46378I7874J0D01*
G01X43709D01*
G02X51583Y38504I0J-7874D01*
G01Y20397D01*
G01X2306Y311361D02*
G03X0Y305793I5568J-5568D01*
G01Y54252D01*
G03X7874Y46378I7874J0D01*
G01X43709D01*
G02X51583Y38504I0J-7874D01*
G01Y20397D01*
G01X2306Y311361D02*
G03X0Y305793I5568J-5568D01*
G01Y54252D01*
G03X7874Y46378I7874J0D01*
G01X43709D01*
G02X51583Y38504I0J-7874D01*
G01Y20397D01*
G01X2306Y311361D02*
G03X0Y305793I5568J-5568D01*
G01Y54252D01*
G03X7874Y46378I7874J0D01*
G01X43709D01*
G02X51583Y38504I0J-7874D01*
G01Y20397D01*
G01X2306Y311361D02*
G03X0Y305793I5568J-5568D01*
G01Y54252D01*
G03X7874Y46378I7874J0D01*
G01X43709D01*
G02X51583Y38504I0J-7874D01*
G01Y20397D01*
G01X2306Y311361D02*
G03X0Y305793I5568J-5568D01*
G01Y54252D01*
G03X7874Y46378I7874J0D01*
G01X43709D01*
G02X51583Y38504I0J-7874D01*
G01Y20397D01*
G01X2306Y311361D02*
G03X0Y305793I5568J-5568D01*
G01Y54252D01*
G03X7874Y46378I7874J0D01*
G01X43709D01*
G02X51583Y38504I0J-7874D01*
G01Y20397D01*
G01X2306Y311361D02*
G03X0Y305793I5568J-5568D01*
G01Y54252D01*
G03X7874Y46378I7874J0D01*
G01X43709D01*
G02X51583Y38504I0J-7874D01*
G01Y20397D01*
G01X2306Y311361D02*
G03X0Y305793I5568J-5568D01*
G01Y54252D01*
G03X7874Y46378I7874J0D01*
G01X43709D01*
G02X51583Y38504I0J-7874D01*
G01Y20397D01*
G01X2306Y311361D02*
G03X0Y305793I5568J-5568D01*
G01Y54252D01*
G03X7874Y46378I7874J0D01*
G01X43709D01*
G02X51583Y38504I0J-7874D01*
G01Y20397D01*
G01X2306Y311361D02*
G03X0Y305793I5568J-5568D01*
G01Y54252D01*
G03X7874Y46378I7874J0D01*
G01X43709D01*
G02X51583Y38504I0J-7874D01*
G01Y20397D01*
G01X2306Y311361D02*
G03X0Y305793I5568J-5568D01*
G01Y54252D01*
G03X7874Y46378I7874J0D01*
G01X43709D01*
G02X51583Y38504I0J-7874D01*
G01Y20397D01*
G01X2306Y311361D02*
G03X0Y305793I5568J-5568D01*
G01Y54252D01*
G03X7874Y46378I7874J0D01*
G01X43709D01*
G02X51583Y38504I0J-7874D01*
G01Y20397D01*
G01X2306Y311361D02*
G03X0Y305793I5568J-5568D01*
G01Y54252D01*
G03X7874Y46378I7874J0D01*
G01X43709D01*
G02X51583Y38504I0J-7874D01*
G01Y20397D01*
G01X2306Y311361D02*
G03X0Y305793I5568J-5568D01*
G01Y54252D01*
G03X7874Y46378I7874J0D01*
G01X43709D01*
G02X51583Y38504I0J-7874D01*
G01Y20397D01*
G01X2306Y311361D02*
G03X0Y305793I5568J-5568D01*
G01Y54252D01*
G03X7874Y46378I7874J0D01*
G01X43709D01*
G02X51583Y38504I0J-7874D01*
G01Y20397D01*
G01X2306Y311361D02*
G03X0Y305793I5568J-5568D01*
G01Y54252D01*
G03X7874Y46378I7874J0D01*
G01X43709D01*
G02X51583Y38504I0J-7874D01*
G01Y20397D01*
G01X2306Y311361D02*
G03X0Y305793I5568J-5568D01*
G01Y54252D01*
G03X7874Y46378I7874J0D01*
G01X43709D01*
G02X51583Y38504I0J-7874D01*
G01Y20397D01*
G01X2306Y311361D02*
G03X0Y305793I5568J-5568D01*
G01Y54252D01*
G03X7874Y46378I7874J0D01*
G01X43709D01*
G02X51583Y38504I0J-7874D01*
G01Y20397D01*
G01X2306Y311361D02*
G03X0Y305793I5568J-5568D01*
G01Y54252D01*
G03X7874Y46378I7874J0D01*
G01X43709D01*
G02X51583Y38504I0J-7874D01*
G01Y20397D01*
G01X2306Y311361D02*
G03X0Y305793I5568J-5568D01*
G01Y54252D01*
G03X7874Y46378I7874J0D01*
G01X43709D01*
G02X51583Y38504I0J-7874D01*
G01Y20397D01*
G01X2306Y311361D02*
G03X0Y305793I5568J-5568D01*
G01Y54252D01*
G03X7874Y46378I7874J0D01*
G01X43709D01*
G02X51583Y38504I0J-7874D01*
G01Y20397D01*
G01X2306Y311361D02*
G03X0Y305793I5568J-5568D01*
G01Y54252D01*
G03X7874Y46378I7874J0D01*
G01X43709D01*
G02X51583Y38504I0J-7874D01*
G01Y20397D01*
G01X2306Y311361D02*
G03X0Y305793I5568J-5568D01*
G01Y54252D01*
G03X7874Y46378I7874J0D01*
G01X43709D01*
G02X51583Y38504I0J-7874D01*
G01Y20397D01*
G01X2306Y311361D02*
G03X0Y305793I5568J-5568D01*
G01Y54252D01*
G03X7874Y46378I7874J0D01*
G01X43709D01*
G02X51583Y38504I0J-7874D01*
G01Y20397D01*
G01X2306Y311361D02*
G03X0Y305793I5568J-5568D01*
G01Y54252D01*
G03X7874Y46378I7874J0D01*
G01X43709D01*
G02X51583Y38504I0J-7874D01*
G01Y20397D01*
G01X2306Y311361D02*
G03X0Y305793I5568J-5568D01*
G01Y54252D01*
G03X7874Y46378I7874J0D01*
G01X43709D01*
G02X51583Y38504I0J-7874D01*
G01Y20397D01*
G01X2306Y311361D02*
G03X0Y305793I5568J-5568D01*
G01Y54252D01*
G03X7874Y46378I7874J0D01*
G01X43709D01*
G02X51583Y38504I0J-7874D01*
G01Y20397D01*
G01X2306Y311361D02*
G03X0Y305793I5568J-5568D01*
G01Y54252D01*
G03X7874Y46378I7874J0D01*
G01X43709D01*
G02X51583Y38504I0J-7874D01*
G01Y20397D01*
G01X2306Y311361D02*
G03X0Y305793I5568J-5568D01*
G01Y54252D01*
G03X7874Y46378I7874J0D01*
G01X43709D01*
G02X51583Y38504I0J-7874D01*
G01Y20397D01*
G01X2306Y311361D02*
G03X0Y305793I5568J-5568D01*
G01Y54252D01*
G03X7874Y46378I7874J0D01*
G01X43709D01*
G02X51583Y38504I0J-7874D01*
G01Y20397D01*
G01X2306Y311361D02*
G03X0Y305793I5568J-5568D01*
G01Y54252D01*
G03X7874Y46378I7874J0D01*
G01X43709D01*
G02X51583Y38504I0J-7874D01*
G01Y20397D01*
G01X2306Y311361D02*
G03X0Y305793I5568J-5568D01*
G01Y54252D01*
G03X7874Y46378I7874J0D01*
G01X43709D01*
G02X51583Y38504I0J-7874D01*
G01Y20397D01*
G01X2306Y311361D02*
G03X0Y305793I5568J-5568D01*
G01Y54252D01*
G03X7874Y46378I7874J0D01*
G01X43709D01*
G02X51583Y38504I0J-7874D01*
G01Y20397D01*
G01X2306Y311361D02*
G03X0Y305793I5568J-5568D01*
G01Y54252D01*
G03X7874Y46378I7874J0D01*
G01X43709D01*
G02X51583Y38504I0J-7874D01*
G01Y20397D01*
G01X2306Y311361D02*
G03X0Y305793I5568J-5568D01*
G01Y54252D01*
G03X7874Y46378I7874J0D01*
G01X43709D01*
G02X51583Y38504I0J-7874D01*
G01Y20397D01*
G01X2306Y311361D02*
G03X0Y305793I5568J-5568D01*
G01Y54252D01*
G03X7874Y46378I7874J0D01*
G01X43709D01*
G02X51583Y38504I0J-7874D01*
G01Y20397D01*
G01X2306Y311361D02*
G03X0Y305793I5568J-5568D01*
G01Y54252D01*
G03X7874Y46378I7874J0D01*
G01X43709D01*
G02X51583Y38504I0J-7874D01*
G01Y20397D01*
G01X2306Y311361D02*
G03X0Y305793I5568J-5568D01*
G01Y54252D01*
G03X7874Y46378I7874J0D01*
G01X43709D01*
G02X51583Y38504I0J-7874D01*
G01Y20397D01*
G01X2306Y311361D02*
G03X0Y305793I5568J-5568D01*
G01Y54252D01*
G03X7874Y46378I7874J0D01*
G01X43709D01*
G02X51583Y38504I0J-7874D01*
G01Y20397D01*
G01X2306Y311361D02*
G03X0Y305793I5568J-5568D01*
G01Y54252D01*
G03X7874Y46378I7874J0D01*
G01X43709D01*
G02X51583Y38504I0J-7874D01*
G01Y20397D01*
G01X2306Y311361D02*
G03X0Y305793I5568J-5568D01*
G01Y54252D01*
G03X7874Y46378I7874J0D01*
G01X43709D01*
G02X51583Y38504I0J-7874D01*
G01Y20397D01*
G01X2306Y311361D02*
G03X0Y305793I5568J-5568D01*
G01Y54252D01*
G03X7874Y46378I7874J0D01*
G01X43709D01*
G02X51583Y38504I0J-7874D01*
G01Y20397D01*
G01X2306Y311361D02*
G03X0Y305793I5568J-5568D01*
G01Y54252D01*
G03X7874Y46378I7874J0D01*
G01X43709D01*
G02X51583Y38504I0J-7874D01*
G01Y20397D01*
G01X2306Y311361D02*
G03X0Y305793I5568J-5568D01*
G01Y54252D01*
G03X7874Y46378I7874J0D01*
G01X43709D01*
G02X51583Y38504I0J-7874D01*
G01Y20397D01*
G01X2306Y311361D02*
G03X0Y305793I5568J-5568D01*
G01Y54252D01*
G03X7874Y46378I7874J0D01*
G01X43709D01*
G02X51583Y38504I0J-7874D01*
G01Y20397D01*
G01X2306Y311361D02*
G03X0Y305793I5568J-5568D01*
G01Y54252D01*
G03X7874Y46378I7874J0D01*
G01X43709D01*
G02X51583Y38504I0J-7874D01*
G01Y20397D01*
G01X2306Y311361D02*
G03X0Y305793I5568J-5568D01*
G01Y54252D01*
G03X7874Y46378I7874J0D01*
G01X43709D01*
G02X51583Y38504I0J-7874D01*
G01Y20397D01*
G01X2306Y311361D02*
G03X0Y305793I5568J-5568D01*
G01Y54252D01*
G03X7874Y46378I7874J0D01*
G01X43709D01*
G02X51583Y38504I0J-7874D01*
G01Y20397D01*
G01X2306Y311361D02*
G03X0Y305793I5568J-5568D01*
G01Y54252D01*
G01X2306Y311361D02*
G03X0Y305793I5568J-5568D01*
G01Y54252D01*
G03X7874Y46378I7874J0D01*
G01X2306Y311361D02*
G03X0Y305793I5568J-5568D01*
G01Y54252D01*
G03X7874Y46378I7874J0D01*
G01X43709D01*
G01X2306Y311361D02*
G03X0Y305793I5568J-5568D01*
G01Y54252D01*
G03X7874Y46378I7874J0D01*
G01X43709D01*
G02X51583Y38504I0J-7874D01*
G01X2306Y311361D02*
G03X0Y305793I5568J-5568D01*
G01Y54252D01*
G03X7874Y46378I7874J0D01*
G01X43709D01*
G02X51583Y38504I0J-7874D01*
G01Y20397D01*
G01X2306Y311361D02*
G03X0Y305793I5568J-5568D01*
G01Y54252D01*
G03X7874Y46378I7874J0D01*
G01X43709D01*
G02X51583Y38504I0J-7874D01*
G01Y20397D01*
G01X2306Y311361D02*
G03X0Y305793I5568J-5568D01*
G01Y54252D01*
G03X7874Y46378I7874J0D01*
G01X43709D01*
G02X51583Y38504I0J-7874D01*
G01Y20397D01*
G01X2306Y311361D02*
G03X0Y305793I5568J-5568D01*
G01Y54252D01*
G03X7874Y46378I7874J0D01*
G01X43709D01*
G02X51583Y38504I0J-7874D01*
G01Y20397D01*
G01X2306Y311361D02*
G03X0Y305793I5568J-5568D01*
G01Y54252D01*
G03X7874Y46378I7874J0D01*
G01X43709D01*
G02X51583Y38504I0J-7874D01*
G01Y20397D01*
G01X2306Y311361D02*
G03X0Y305793I5568J-5568D01*
G01Y54252D01*
G03X7874Y46378I7874J0D01*
G01X43709D01*
G02X51583Y38504I0J-7874D01*
G01Y20397D01*
G01X2306Y311361D02*
G03X0Y305793I5568J-5568D01*
G01Y54252D01*
G03X7874Y46378I7874J0D01*
G01X43709D01*
G02X51583Y38504I0J-7874D01*
G01Y20397D01*
G01X2306Y311361D02*
G03X0Y305793I5568J-5568D01*
G01Y54252D01*
G03X7874Y46378I7874J0D01*
G01X43709D01*
G02X51583Y38504I0J-7874D01*
G01Y20397D01*
G01X2306Y311361D02*
G03X0Y305793I5568J-5568D01*
G01Y54252D01*
G03X7874Y46378I7874J0D01*
G01X43709D01*
G02X51583Y38504I0J-7874D01*
G01Y20397D01*
G01X2306Y311361D02*
G03X0Y305793I5568J-5568D01*
G01Y54252D01*
G03X7874Y46378I7874J0D01*
G01X43709D01*
G02X51583Y38504I0J-7874D01*
G01Y20397D01*
G01X2306Y311361D02*
G03X0Y305793I5568J-5568D01*
G01Y54252D01*
G03X7874Y46378I7874J0D01*
G01X43709D01*
G02X51583Y38504I0J-7874D01*
G01Y20397D01*
G01X2306Y311361D02*
G03X0Y305793I5568J-5568D01*
G01Y54252D01*
G03X7874Y46378I7874J0D01*
G01X43709D01*
G02X51583Y38504I0J-7874D01*
G01Y20397D01*
G01X2306Y311361D02*
G03X0Y305793I5568J-5568D01*
G01Y54252D01*
G03X7874Y46378I7874J0D01*
G01X43709D01*
G02X51583Y38504I0J-7874D01*
G01Y20397D01*
G01X2306Y311361D02*
G03X0Y305793I5568J-5568D01*
G01Y54252D01*
G03X7874Y46378I7874J0D01*
G01X43709D01*
G02X51583Y38504I0J-7874D01*
G01Y20397D01*
G01X2306Y311361D02*
G03X0Y305793I5568J-5568D01*
G01Y54252D01*
G03X7874Y46378I7874J0D01*
G01X43709D01*
G02X51583Y38504I0J-7874D01*
G01Y20397D01*
G01X2306Y311361D02*
G03X0Y305793I5568J-5568D01*
G01Y54252D01*
G03X7874Y46378I7874J0D01*
G01X43709D01*
G02X51583Y38504I0J-7874D01*
G01Y20397D01*
G01X2306Y311361D02*
G03X0Y305793I5568J-5568D01*
G01Y54252D01*
G03X7874Y46378I7874J0D01*
G01X43709D01*
G02X51583Y38504I0J-7874D01*
G01Y20397D01*
G01X2306Y311361D02*
G03X0Y305793I5568J-5568D01*
G01Y54252D01*
G03X7874Y46378I7874J0D01*
G01X43709D01*
G02X51583Y38504I0J-7874D01*
G01Y20397D01*
G01X2306Y311361D02*
G03X0Y305793I5568J-5568D01*
G01Y54252D01*
G03X7874Y46378I7874J0D01*
G01X43709D01*
G02X51583Y38504I0J-7874D01*
G01Y20397D01*
G01X2306Y311361D02*
G03X0Y305793I5568J-5568D01*
G01Y54252D01*
G03X7874Y46378I7874J0D01*
G01X43709D01*
G02X51583Y38504I0J-7874D01*
G01Y20397D01*
G01X2306Y311361D02*
G03X0Y305793I5568J-5568D01*
G01Y54252D01*
G03X7874Y46378I7874J0D01*
G01X43709D01*
G02X51583Y38504I0J-7874D01*
G01Y20397D01*
G01X2306Y311361D02*
G03X0Y305793I5568J-5568D01*
G01Y54252D01*
G03X7874Y46378I7874J0D01*
G01X43709D01*
G02X51583Y38504I0J-7874D01*
G01Y20397D01*
G01X2306Y311361D02*
G03X0Y305793I5568J-5568D01*
G01Y54252D01*
G03X7874Y46378I7874J0D01*
G01X43709D01*
G02X51583Y38504I0J-7874D01*
G01Y20397D01*
G01X2306Y311361D02*
G03X0Y305793I5568J-5568D01*
G01Y54252D01*
G03X7874Y46378I7874J0D01*
G01X43709D01*
G02X51583Y38504I0J-7874D01*
G01Y20397D01*
G01X2306Y311361D02*
G03X0Y305793I5568J-5568D01*
G01Y54252D01*
G03X7874Y46378I7874J0D01*
G01X43709D01*
G02X51583Y38504I0J-7874D01*
G01Y20397D01*
G01X2306Y311361D02*
G03X0Y305793I5568J-5568D01*
G01Y54252D01*
G03X7874Y46378I7874J0D01*
G01X43709D01*
G02X51583Y38504I0J-7874D01*
G01Y20397D01*
G01X2306Y311361D02*
G03X0Y305793I5568J-5568D01*
G01Y54252D01*
G03X7874Y46378I7874J0D01*
G01X43709D01*
G02X51583Y38504I0J-7874D01*
G01Y20397D01*
G01X2306Y311361D02*
G03X0Y305793I5568J-5568D01*
G01Y54252D01*
G03X7874Y46378I7874J0D01*
G01X43709D01*
G02X51583Y38504I0J-7874D01*
G01Y20397D01*
G01X2306Y311361D02*
G03X0Y305793I5568J-5568D01*
G01Y54252D01*
G03X7874Y46378I7874J0D01*
G01X43709D01*
G02X51583Y38504I0J-7874D01*
G01Y20397D01*
G01X2306Y311361D02*
G03X0Y305793I5568J-5568D01*
G01Y54252D01*
G03X7874Y46378I7874J0D01*
G01X43709D01*
G02X51583Y38504I0J-7874D01*
G01Y20397D01*
G01X2306Y311361D02*
G03X0Y305793I5568J-5568D01*
G01Y54252D01*
G03X7874Y46378I7874J0D01*
G01X43709D01*
G02X51583Y38504I0J-7874D01*
G01Y20397D01*
G01X2306Y311361D02*
G03X0Y305793I5568J-5568D01*
G01Y54252D01*
G03X7874Y46378I7874J0D01*
G01X43709D01*
G02X51583Y38504I0J-7874D01*
G01Y20397D01*
G01X2306Y311361D02*
G03X0Y305793I5568J-5568D01*
G01Y54252D01*
G03X7874Y46378I7874J0D01*
G01X43709D01*
G02X51583Y38504I0J-7874D01*
G01Y20397D01*
G01X2306Y311361D02*
G03X0Y305793I5568J-5568D01*
G01Y54252D01*
G03X7874Y46378I7874J0D01*
G01X43709D01*
G02X51583Y38504I0J-7874D01*
G01Y20397D01*
G01X2306Y311361D02*
G03X0Y305793I5568J-5568D01*
G01Y54252D01*
G03X7874Y46378I7874J0D01*
G01X43709D01*
G02X51583Y38504I0J-7874D01*
G01Y20397D01*
G01X2306Y311361D02*
G03X0Y305793I5568J-5568D01*
G01Y54252D01*
G03X7874Y46378I7874J0D01*
G01X43709D01*
G02X51583Y38504I0J-7874D01*
G01Y20397D01*
G01X2306Y311361D02*
G03X0Y305793I5568J-5568D01*
G01Y54252D01*
G03X7874Y46378I7874J0D01*
G01X43709D01*
G02X51583Y38504I0J-7874D01*
G01Y20397D01*
G01X2306Y311361D02*
G03X0Y305793I5568J-5568D01*
G01Y54252D01*
G03X7874Y46378I7874J0D01*
G01X43709D01*
G02X51583Y38504I0J-7874D01*
G01Y20397D01*
G01X2306Y311361D02*
G03X0Y305793I5568J-5568D01*
G01Y54252D01*
G03X7874Y46378I7874J0D01*
G01X43709D01*
G02X51583Y38504I0J-7874D01*
G01Y20397D01*
G01X2306Y311361D02*
G03X0Y305793I5568J-5568D01*
G01Y54252D01*
G03X7874Y46378I7874J0D01*
G01X43709D01*
G02X51583Y38504I0J-7874D01*
G01Y20397D01*
G01X2306Y311361D02*
G03X0Y305793I5568J-5568D01*
G01Y54252D01*
G03X7874Y46378I7874J0D01*
G01X43709D01*
G02X51583Y38504I0J-7874D01*
G01Y20397D01*
G01X2306Y311361D02*
G03X0Y305793I5568J-5568D01*
G01Y54252D01*
G03X7874Y46378I7874J0D01*
G01X43709D01*
G02X51583Y38504I0J-7874D01*
G01Y20397D01*
G01X2306Y311361D02*
G03X0Y305793I5568J-5568D01*
G01Y54252D01*
G03X7874Y46378I7874J0D01*
G01X43709D01*
G02X51583Y38504I0J-7874D01*
G01Y20397D01*
G01X2306Y311361D02*
G03X0Y305793I5568J-5568D01*
G01Y54252D01*
G03X7874Y46378I7874J0D01*
G01X43709D01*
G02X51583Y38504I0J-7874D01*
G01Y20397D01*
G01X2306Y311361D02*
G03X0Y305793I5568J-5568D01*
G01Y54252D01*
G03X7874Y46378I7874J0D01*
G01X43709D01*
G02X51583Y38504I0J-7874D01*
G01Y20397D01*
G01X2306Y311361D02*
G03X0Y305793I5568J-5568D01*
G01Y54252D01*
G03X7874Y46378I7874J0D01*
G01X43709D01*
G02X51583Y38504I0J-7874D01*
G01Y20397D01*
G01X2306Y311361D02*
G03X0Y305793I5568J-5568D01*
G01Y54252D01*
G03X7874Y46378I7874J0D01*
G01X43709D01*
G02X51583Y38504I0J-7874D01*
G01Y20397D01*
G01X2306Y311361D02*
G03X0Y305793I5568J-5568D01*
G01Y54252D01*
G03X7874Y46378I7874J0D01*
G01X43709D01*
G02X51583Y38504I0J-7874D01*
G01Y20397D01*
G01X2306Y311361D02*
G03X0Y305793I5568J-5568D01*
G01Y54252D01*
G03X7874Y46378I7874J0D01*
G01X43709D01*
G02X51583Y38504I0J-7874D01*
G01Y20397D01*
G01X2306Y311361D02*
G03X0Y305793I5568J-5568D01*
G01Y54252D01*
G03X7874Y46378I7874J0D01*
G01X43709D01*
G02X51583Y38504I0J-7874D01*
G01Y20397D01*
G01X2306Y311361D02*
G03X0Y305793I5568J-5568D01*
G01Y54252D01*
G03X7874Y46378I7874J0D01*
G01X43709D01*
G02X51583Y38504I0J-7874D01*
G01Y20397D01*
G01X2306Y311361D02*
G03X0Y305793I5568J-5568D01*
G01Y54252D01*
G03X7874Y46378I7874J0D01*
G01X43709D01*
G02X51583Y38504I0J-7874D01*
G01Y20397D01*
G01X2306Y311361D02*
G03X0Y305793I5568J-5568D01*
G01Y54252D01*
G03X7874Y46378I7874J0D01*
G01X43709D01*
G02X51583Y38504I0J-7874D01*
G01Y20397D01*
G01X2306Y311361D02*
G03X0Y305793I5568J-5568D01*
G01Y54252D01*
G03X7874Y46378I7874J0D01*
G01X43709D01*
G02X51583Y38504I0J-7874D01*
G01Y20397D01*
G01X2306Y311361D02*
G03X0Y305793I5568J-5568D01*
G01Y54252D01*
G03X7874Y46378I7874J0D01*
G01X43709D01*
G02X51583Y38504I0J-7874D01*
G01Y20397D01*
G01X2306Y311361D02*
G03X0Y305793I5568J-5568D01*
G01Y54252D01*
G03X7874Y46378I7874J0D01*
G01X43709D01*
G02X51583Y38504I0J-7874D01*
G01Y20397D01*
G01X2306Y311361D02*
G03X0Y305793I5568J-5568D01*
G01Y54252D01*
G03X7874Y46378I7874J0D01*
G01X43709D01*
G02X51583Y38504I0J-7874D01*
G01Y20397D01*
G01X2306Y311361D02*
G03X0Y305793I5568J-5568D01*
G01Y54252D01*
G03X7874Y46378I7874J0D01*
G01X43709D01*
G02X51583Y38504I0J-7874D01*
G01Y20397D01*
G01Y1969D02*
Y38504D01*
G03X43709Y46378I-7874J0D01*
G01X7874D01*
G02X0Y54252I0J7874D01*
G01Y305793D01*
G02X2306Y311361I7874J0D01*
G01D02*
G03X0Y305794I5567J-5567D01*
G01Y54252D01*
G01X2306Y311361D02*
G03X0Y305794I5567J-5567D01*
G01Y54252D01*
G03X7874Y46378I7874J0D01*
G01X2306Y311361D02*
G03X0Y305794I5567J-5567D01*
G01Y54252D01*
G03X7874Y46378I7874J0D01*
G01X43709D01*
G01X2306Y311361D02*
G03X0Y305794I5567J-5567D01*
G01Y54252D01*
G03X7874Y46378I7874J0D01*
G01X43709D01*
G02X51583Y38504I0J-7874D01*
G01X2306Y311361D02*
G03X0Y305794I5567J-5567D01*
G01Y54252D01*
G03X7874Y46378I7874J0D01*
G01X43709D01*
G02X51583Y38504I0J-7874D01*
G01Y1969D01*
G01X2306Y311361D02*
G03X0Y305794I5567J-5567D01*
G01Y54252D01*
G03X7874Y46378I7874J0D01*
G01X43709D01*
G02X51583Y38504I0J-7874D01*
G01Y1969D01*
G03X53551Y0I1968J0D01*
G01X2306Y311361D02*
G03X0Y305794I5567J-5567D01*
G01Y54252D01*
G03X7874Y46378I7874J0D01*
G01X43709D01*
G02X51583Y38504I0J-7874D01*
G01Y1969D01*
G03X53551Y0I1968J0D01*
G01X319693D01*
G01X2306Y311361D02*
G03X0Y305794I5567J-5567D01*
G01Y54252D01*
G03X7874Y46378I7874J0D01*
G01X43709D01*
G02X51583Y38504I0J-7874D01*
G01Y1969D01*
G03X53551Y0I1968J0D01*
G01X319693D01*
G03X321661Y1969I0J1969D01*
G01X2306Y311361D02*
G03X0Y305794I5567J-5567D01*
G01Y54252D01*
G03X7874Y46378I7874J0D01*
G01X43709D01*
G02X51583Y38504I0J-7874D01*
G01Y1969D01*
G03X53551Y0I1968J0D01*
G01X319693D01*
G03X321661Y1969I0J1969D01*
G01Y38504D01*
G01X2306Y311361D02*
G03X0Y305794I5567J-5567D01*
G01Y54252D01*
G03X7874Y46378I7874J0D01*
G01X43709D01*
G02X51583Y38504I0J-7874D01*
G01Y1969D01*
G03X53551Y0I1968J0D01*
G01X319693D01*
G03X321661Y1969I0J1969D01*
G01Y38504D01*
G02X329535Y46378I7874J0D01*
G01X2306Y311361D02*
G03X0Y305794I5567J-5567D01*
G01Y54252D01*
G03X7874Y46378I7874J0D01*
G01X43709D01*
G02X51583Y38504I0J-7874D01*
G01Y1969D01*
G03X53551Y0I1968J0D01*
G01X319693D01*
G03X321661Y1969I0J1969D01*
G01Y38504D01*
G02X329535Y46378I7874J0D01*
G01X488591D01*
G01X2306Y311361D02*
G03X0Y305794I5567J-5567D01*
G01Y54252D01*
G03X7874Y46378I7874J0D01*
G01X43709D01*
G02X51583Y38504I0J-7874D01*
G01Y1969D01*
G03X53551Y0I1968J0D01*
G01X319693D01*
G03X321661Y1969I0J1969D01*
G01Y38504D01*
G02X329535Y46378I7874J0D01*
G01X488591D01*
G02X496465Y38504I0J-7874D01*
G01X2306Y311361D02*
G03X0Y305794I5567J-5567D01*
G01Y54252D01*
G03X7874Y46378I7874J0D01*
G01X43709D01*
G02X51583Y38504I0J-7874D01*
G01Y1969D01*
G03X53551Y0I1968J0D01*
G01X319693D01*
G03X321661Y1969I0J1969D01*
G01Y38504D01*
G02X329535Y46378I7874J0D01*
G01X488591D01*
G02X496465Y38504I0J-7874D01*
G01Y22756D01*
G01X2306Y311361D02*
G03X0Y305794I5567J-5567D01*
G01Y54252D01*
G03X7874Y46378I7874J0D01*
G01X43709D01*
G02X51583Y38504I0J-7874D01*
G01Y1969D01*
G03X53551Y0I1968J0D01*
G01X319693D01*
G03X321661Y1969I0J1969D01*
G01Y38504D01*
G02X329535Y46378I7874J0D01*
G01X488591D01*
G02X496465Y38504I0J-7874D01*
G01Y22756D01*
G03X498433Y20787I1968J-1D01*
G01X2306Y311361D02*
G03X0Y305794I5567J-5567D01*
G01Y54252D01*
G03X7874Y46378I7874J0D01*
G01X43709D01*
G02X51583Y38504I0J-7874D01*
G01Y1969D01*
G03X53551Y0I1968J0D01*
G01X319693D01*
G03X321661Y1969I0J1969D01*
G01Y38504D01*
G02X329535Y46378I7874J0D01*
G01X488591D01*
G02X496465Y38504I0J-7874D01*
G01Y22756D01*
G03X498433Y20787I1968J-1D01*
G01X764575D01*
G01X2306Y311361D02*
G03X0Y305794I5567J-5567D01*
G01Y54252D01*
G03X7874Y46378I7874J0D01*
G01X43709D01*
G02X51583Y38504I0J-7874D01*
G01Y1969D01*
G03X53551Y0I1968J0D01*
G01X319693D01*
G03X321661Y1969I0J1969D01*
G01Y38504D01*
G02X329535Y46378I7874J0D01*
G01X488591D01*
G02X496465Y38504I0J-7874D01*
G01Y22756D01*
G03X498433Y20787I1968J-1D01*
G01X764575D01*
G03X766543Y22756I-1J1969D01*
G01X2306Y311361D02*
G03X0Y305794I5567J-5567D01*
G01Y54252D01*
G03X7874Y46378I7874J0D01*
G01X43709D01*
G02X51583Y38504I0J-7874D01*
G01Y1969D01*
G03X53551Y0I1968J0D01*
G01X319693D01*
G03X321661Y1969I0J1969D01*
G01Y38504D01*
G02X329535Y46378I7874J0D01*
G01X488591D01*
G02X496465Y38504I0J-7874D01*
G01Y22756D01*
G03X498433Y20787I1968J-1D01*
G01X764575D01*
G03X766543Y22756I-1J1969D01*
G01Y38504D01*
G01X2306Y311361D02*
G03X0Y305794I5567J-5567D01*
G01Y54252D01*
G03X7874Y46378I7874J0D01*
G01X43709D01*
G02X51583Y38504I0J-7874D01*
G01Y1969D01*
G03X53551Y0I1968J0D01*
G01X319693D01*
G03X321661Y1969I0J1969D01*
G01Y38504D01*
G02X329535Y46378I7874J0D01*
G01X488591D01*
G02X496465Y38504I0J-7874D01*
G01Y22756D01*
G03X498433Y20787I1968J-1D01*
G01X764575D01*
G03X766543Y22756I-1J1969D01*
G01Y38504D01*
G02X774417Y46378I7874J0D01*
G01X2306Y311361D02*
G03X0Y305794I5567J-5567D01*
G01Y54252D01*
G03X7874Y46378I7874J0D01*
G01X43709D01*
G02X51583Y38504I0J-7874D01*
G01Y1969D01*
G03X53551Y0I1968J0D01*
G01X319693D01*
G03X321661Y1969I0J1969D01*
G01Y38504D01*
G02X329535Y46378I7874J0D01*
G01X488591D01*
G02X496465Y38504I0J-7874D01*
G01Y22756D01*
G03X498433Y20787I1968J-1D01*
G01X764575D01*
G03X766543Y22756I-1J1969D01*
G01Y38504D01*
G02X774417Y46378I7874J0D01*
G01X871260D01*
G01X2306Y311361D02*
G03X0Y305794I5567J-5567D01*
G01Y54252D01*
G03X7874Y46378I7874J0D01*
G01X43709D01*
G02X51583Y38504I0J-7874D01*
G01Y1969D01*
G03X53551Y0I1968J0D01*
G01X319693D01*
G03X321661Y1969I0J1969D01*
G01Y38504D01*
G02X329535Y46378I7874J0D01*
G01X488591D01*
G02X496465Y38504I0J-7874D01*
G01Y22756D01*
G03X498433Y20787I1968J-1D01*
G01X764575D01*
G03X766543Y22756I-1J1969D01*
G01Y38504D01*
G02X774417Y46378I7874J0D01*
G01X871260D01*
G03X879134Y54252I0J7874D01*
G01X2306Y311361D02*
G03X0Y305794I5567J-5567D01*
G01Y54252D01*
G03X7874Y46378I7874J0D01*
G01X43709D01*
G02X51583Y38504I0J-7874D01*
G01Y1969D01*
G03X53551Y0I1968J0D01*
G01X319693D01*
G03X321661Y1969I0J1969D01*
G01Y38504D01*
G02X329535Y46378I7874J0D01*
G01X488591D01*
G02X496465Y38504I0J-7874D01*
G01Y22756D01*
G03X498433Y20787I1968J-1D01*
G01X764575D01*
G03X766543Y22756I-1J1969D01*
G01Y38504D01*
G02X774417Y46378I7874J0D01*
G01X871260D01*
G03X879134Y54252I0J7874D01*
G01Y134331D01*
G01X2306Y311361D02*
G03X0Y305794I5567J-5567D01*
G01Y54252D01*
G03X7874Y46378I7874J0D01*
G01X43709D01*
G02X51583Y38504I0J-7874D01*
G01Y1969D01*
G03X53551Y0I1968J0D01*
G01X319693D01*
G03X321661Y1969I0J1969D01*
G01Y38504D01*
G02X329535Y46378I7874J0D01*
G01X488591D01*
G02X496465Y38504I0J-7874D01*
G01Y22756D01*
G03X498433Y20787I1968J-1D01*
G01X764575D01*
G03X766543Y22756I-1J1969D01*
G01Y38504D01*
G02X774417Y46378I7874J0D01*
G01X871260D01*
G03X879134Y54252I0J7874D01*
G01Y134331D01*
G02X887008Y142205I7874J0D01*
G01X2306Y311361D02*
G03X0Y305794I5567J-5567D01*
G01Y54252D01*
G03X7874Y46378I7874J0D01*
G01X43709D01*
G02X51583Y38504I0J-7874D01*
G01Y1969D01*
G03X53551Y0I1968J0D01*
G01X319693D01*
G03X321661Y1969I0J1969D01*
G01Y38504D01*
G02X329535Y46378I7874J0D01*
G01X488591D01*
G02X496465Y38504I0J-7874D01*
G01Y22756D01*
G03X498433Y20787I1968J-1D01*
G01X764575D01*
G03X766543Y22756I-1J1969D01*
G01Y38504D01*
G02X774417Y46378I7874J0D01*
G01X871260D01*
G03X879134Y54252I0J7874D01*
G01Y134331D01*
G02X887008Y142205I7874J0D01*
G01X1011024D01*
G01X2306Y311361D02*
G03X0Y305794I5567J-5567D01*
G01Y54252D01*
G03X7874Y46378I7874J0D01*
G01X43709D01*
G02X51583Y38504I0J-7874D01*
G01Y1969D01*
G03X53551Y0I1968J0D01*
G01X319693D01*
G03X321661Y1969I0J1969D01*
G01Y38504D01*
G02X329535Y46378I7874J0D01*
G01X488591D01*
G02X496465Y38504I0J-7874D01*
G01Y22756D01*
G03X498433Y20787I1968J-1D01*
G01X764575D01*
G03X766543Y22756I-1J1969D01*
G01Y38504D01*
G02X774417Y46378I7874J0D01*
G01X871260D01*
G03X879134Y54252I0J7874D01*
G01Y134331D01*
G02X887008Y142205I7874J0D01*
G01X1011024D01*
G02X1018898Y134331I0J-7874D01*
G01X2306Y311361D02*
G03X0Y305794I5567J-5567D01*
G01Y54252D01*
G03X7874Y46378I7874J0D01*
G01X43709D01*
G02X51583Y38504I0J-7874D01*
G01Y1969D01*
G03X53551Y0I1968J0D01*
G01X319693D01*
G03X321661Y1969I0J1969D01*
G01Y38504D01*
G02X329535Y46378I7874J0D01*
G01X488591D01*
G02X496465Y38504I0J-7874D01*
G01Y22756D01*
G03X498433Y20787I1968J-1D01*
G01X764575D01*
G03X766543Y22756I-1J1969D01*
G01Y38504D01*
G02X774417Y46378I7874J0D01*
G01X871260D01*
G03X879134Y54252I0J7874D01*
G01Y134331D01*
G02X887008Y142205I7874J0D01*
G01X1011024D01*
G02X1018898Y134331I0J-7874D01*
G01Y54252D01*
G01X2306Y311361D02*
G03X0Y305794I5567J-5567D01*
G01Y54252D01*
G03X7874Y46378I7874J0D01*
G01X43709D01*
G02X51583Y38504I0J-7874D01*
G01Y1969D01*
G03X53551Y0I1968J0D01*
G01X319693D01*
G03X321661Y1969I0J1969D01*
G01Y38504D01*
G02X329535Y46378I7874J0D01*
G01X488591D01*
G02X496465Y38504I0J-7874D01*
G01Y22756D01*
G03X498433Y20787I1968J-1D01*
G01X764575D01*
G03X766543Y22756I-1J1969D01*
G01Y38504D01*
G02X774417Y46378I7874J0D01*
G01X871260D01*
G03X879134Y54252I0J7874D01*
G01Y134331D01*
G02X887008Y142205I7874J0D01*
G01X1011024D01*
G02X1018898Y134331I0J-7874D01*
G01Y54252D01*
G03X1026772Y46378I7874J0D01*
G01X2306Y311361D02*
G03X0Y305794I5567J-5567D01*
G01Y54252D01*
G03X7874Y46378I7874J0D01*
G01X43709D01*
G02X51583Y38504I0J-7874D01*
G01Y1969D01*
G03X53551Y0I1968J0D01*
G01X319693D01*
G03X321661Y1969I0J1969D01*
G01Y38504D01*
G02X329535Y46378I7874J0D01*
G01X488591D01*
G02X496465Y38504I0J-7874D01*
G01Y22756D01*
G03X498433Y20787I1968J-1D01*
G01X764575D01*
G03X766543Y22756I-1J1969D01*
G01Y38504D01*
G02X774417Y46378I7874J0D01*
G01X871260D01*
G03X879134Y54252I0J7874D01*
G01Y134331D01*
G02X887008Y142205I7874J0D01*
G01X1011024D01*
G02X1018898Y134331I0J-7874D01*
G01Y54252D01*
G03X1026772Y46378I7874J0D01*
G01X1518118D01*
G01X2306Y311361D02*
G03X0Y305794I5567J-5567D01*
G01Y54252D01*
G03X7874Y46378I7874J0D01*
G01X43709D01*
G02X51583Y38504I0J-7874D01*
G01Y1969D01*
G03X53551Y0I1968J0D01*
G01X319693D01*
G03X321661Y1969I0J1969D01*
G01Y38504D01*
G02X329535Y46378I7874J0D01*
G01X488591D01*
G02X496465Y38504I0J-7874D01*
G01Y22756D01*
G03X498433Y20787I1968J-1D01*
G01X764575D01*
G03X766543Y22756I-1J1969D01*
G01Y38504D01*
G02X774417Y46378I7874J0D01*
G01X871260D01*
G03X879134Y54252I0J7874D01*
G01Y134331D01*
G02X887008Y142205I7874J0D01*
G01X1011024D01*
G02X1018898Y134331I0J-7874D01*
G01Y54252D01*
G03X1026772Y46378I7874J0D01*
G01X1518118D01*
G02X1525992Y38504I0J-7874D01*
G01X2306Y311361D02*
G03X0Y305794I5567J-5567D01*
G01Y54252D01*
G03X7874Y46378I7874J0D01*
G01X43709D01*
G02X51583Y38504I0J-7874D01*
G01Y1969D01*
G03X53551Y0I1968J0D01*
G01X319693D01*
G03X321661Y1969I0J1969D01*
G01Y38504D01*
G02X329535Y46378I7874J0D01*
G01X488591D01*
G02X496465Y38504I0J-7874D01*
G01Y22756D01*
G03X498433Y20787I1968J-1D01*
G01X764575D01*
G03X766543Y22756I-1J1969D01*
G01Y38504D01*
G02X774417Y46378I7874J0D01*
G01X871260D01*
G03X879134Y54252I0J7874D01*
G01Y134331D01*
G02X887008Y142205I7874J0D01*
G01X1011024D01*
G02X1018898Y134331I0J-7874D01*
G01Y54252D01*
G03X1026772Y46378I7874J0D01*
G01X1518118D01*
G02X1525992Y38504I0J-7874D01*
G01Y1969D01*
G01X2306Y311361D02*
G03X0Y305794I5567J-5567D01*
G01Y54252D01*
G03X7874Y46378I7874J0D01*
G01X43709D01*
G02X51583Y38504I0J-7874D01*
G01Y1969D01*
G03X53551Y0I1968J0D01*
G01X319693D01*
G03X321661Y1969I0J1969D01*
G01Y38504D01*
G02X329535Y46378I7874J0D01*
G01X488591D01*
G02X496465Y38504I0J-7874D01*
G01Y22756D01*
G03X498433Y20787I1968J-1D01*
G01X764575D01*
G03X766543Y22756I-1J1969D01*
G01Y38504D01*
G02X774417Y46378I7874J0D01*
G01X871260D01*
G03X879134Y54252I0J7874D01*
G01Y134331D01*
G02X887008Y142205I7874J0D01*
G01X1011024D01*
G02X1018898Y134331I0J-7874D01*
G01Y54252D01*
G03X1026772Y46378I7874J0D01*
G01X1518118D01*
G02X1525992Y38504I0J-7874D01*
G01Y1969D01*
G03X1527961Y0I1969J0D01*
G01X2306Y311361D02*
G03X0Y305794I5567J-5567D01*
G01Y54252D01*
G03X7874Y46378I7874J0D01*
G01X43709D01*
G02X51583Y38504I0J-7874D01*
G01Y1969D01*
G03X53551Y0I1968J0D01*
G01X319693D01*
G03X321661Y1969I0J1969D01*
G01Y38504D01*
G02X329535Y46378I7874J0D01*
G01X488591D01*
G02X496465Y38504I0J-7874D01*
G01Y22756D01*
G03X498433Y20787I1968J-1D01*
G01X764575D01*
G03X766543Y22756I-1J1969D01*
G01Y38504D01*
G02X774417Y46378I7874J0D01*
G01X871260D01*
G03X879134Y54252I0J7874D01*
G01Y134331D01*
G02X887008Y142205I7874J0D01*
G01X1011024D01*
G02X1018898Y134331I0J-7874D01*
G01Y54252D01*
G03X1026772Y46378I7874J0D01*
G01X1518118D01*
G02X1525992Y38504I0J-7874D01*
G01Y1969D01*
G03X1527961Y0I1969J0D01*
G01X1794102D01*
G01X2306Y311361D02*
G03X0Y305794I5567J-5567D01*
G01Y54252D01*
G03X7874Y46378I7874J0D01*
G01X43709D01*
G02X51583Y38504I0J-7874D01*
G01Y1969D01*
G03X53551Y0I1968J0D01*
G01X319693D01*
G03X321661Y1969I0J1969D01*
G01Y38504D01*
G02X329535Y46378I7874J0D01*
G01X488591D01*
G02X496465Y38504I0J-7874D01*
G01Y22756D01*
G03X498433Y20787I1968J-1D01*
G01X764575D01*
G03X766543Y22756I-1J1969D01*
G01Y38504D01*
G02X774417Y46378I7874J0D01*
G01X871260D01*
G03X879134Y54252I0J7874D01*
G01Y134331D01*
G02X887008Y142205I7874J0D01*
G01X1011024D01*
G02X1018898Y134331I0J-7874D01*
G01Y54252D01*
G03X1026772Y46378I7874J0D01*
G01X1518118D01*
G02X1525992Y38504I0J-7874D01*
G01Y1969D01*
G03X1527961Y0I1969J0D01*
G01X1794102D01*
G03X1796071Y1969I0J1969D01*
G01X2306Y311361D02*
G03X0Y305794I5567J-5567D01*
G01Y54252D01*
G03X7874Y46378I7874J0D01*
G01X43709D01*
G02X51583Y38504I0J-7874D01*
G01Y1969D01*
G03X53551Y0I1968J0D01*
G01X319693D01*
G03X321661Y1969I0J1969D01*
G01Y38504D01*
G02X329535Y46378I7874J0D01*
G01X488591D01*
G02X496465Y38504I0J-7874D01*
G01Y22756D01*
G03X498433Y20787I1968J-1D01*
G01X764575D01*
G03X766543Y22756I-1J1969D01*
G01Y38504D01*
G02X774417Y46378I7874J0D01*
G01X871260D01*
G03X879134Y54252I0J7874D01*
G01Y134331D01*
G02X887008Y142205I7874J0D01*
G01X1011024D01*
G02X1018898Y134331I0J-7874D01*
G01Y54252D01*
G03X1026772Y46378I7874J0D01*
G01X1518118D01*
G02X1525992Y38504I0J-7874D01*
G01Y1969D01*
G03X1527961Y0I1969J0D01*
G01X1794102D01*
G03X1796071Y1969I0J1969D01*
G01Y38504D01*
G01X2306Y311361D02*
G03X0Y305794I5567J-5567D01*
G01Y54252D01*
G03X7874Y46378I7874J0D01*
G01X43709D01*
G02X51583Y38504I0J-7874D01*
G01Y1969D01*
G03X53551Y0I1968J0D01*
G01X319693D01*
G03X321661Y1969I0J1969D01*
G01Y38504D01*
G02X329535Y46378I7874J0D01*
G01X488591D01*
G02X496465Y38504I0J-7874D01*
G01Y22756D01*
G03X498433Y20787I1968J-1D01*
G01X764575D01*
G03X766543Y22756I-1J1969D01*
G01Y38504D01*
G02X774417Y46378I7874J0D01*
G01X871260D01*
G03X879134Y54252I0J7874D01*
G01Y134331D01*
G02X887008Y142205I7874J0D01*
G01X1011024D01*
G02X1018898Y134331I0J-7874D01*
G01Y54252D01*
G03X1026772Y46378I7874J0D01*
G01X1518118D01*
G02X1525992Y38504I0J-7874D01*
G01Y1969D01*
G03X1527961Y0I1969J0D01*
G01X1794102D01*
G03X1796071Y1969I0J1969D01*
G01Y38504D01*
G02X1803945Y46378I7874J0D01*
G01X2306Y311361D02*
G03X0Y305794I5567J-5567D01*
G01Y54252D01*
G03X7874Y46378I7874J0D01*
G01X43709D01*
G02X51583Y38504I0J-7874D01*
G01Y1969D01*
G03X53551Y0I1968J0D01*
G01X319693D01*
G03X321661Y1969I0J1969D01*
G01Y38504D01*
G02X329535Y46378I7874J0D01*
G01X488591D01*
G02X496465Y38504I0J-7874D01*
G01Y22756D01*
G03X498433Y20787I1968J-1D01*
G01X764575D01*
G03X766543Y22756I-1J1969D01*
G01Y38504D01*
G02X774417Y46378I7874J0D01*
G01X871260D01*
G03X879134Y54252I0J7874D01*
G01Y134331D01*
G02X887008Y142205I7874J0D01*
G01X1011024D01*
G02X1018898Y134331I0J-7874D01*
G01Y54252D01*
G03X1026772Y46378I7874J0D01*
G01X1518118D01*
G02X1525992Y38504I0J-7874D01*
G01Y1969D01*
G03X1527961Y0I1969J0D01*
G01X1794102D01*
G03X1796071Y1969I0J1969D01*
G01Y38504D01*
G02X1803945Y46378I7874J0D01*
G01X1849606D01*
G01X2306Y311361D02*
G03X0Y305794I5567J-5567D01*
G01Y54252D01*
G03X7874Y46378I7874J0D01*
G01X43709D01*
G02X51583Y38504I0J-7874D01*
G01Y1969D01*
G03X53551Y0I1968J0D01*
G01X319693D01*
G03X321661Y1969I0J1969D01*
G01Y38504D01*
G02X329535Y46378I7874J0D01*
G01X488591D01*
G02X496465Y38504I0J-7874D01*
G01Y22756D01*
G03X498433Y20787I1968J-1D01*
G01X764575D01*
G03X766543Y22756I-1J1969D01*
G01Y38504D01*
G02X774417Y46378I7874J0D01*
G01X871260D01*
G03X879134Y54252I0J7874D01*
G01Y134331D01*
G02X887008Y142205I7874J0D01*
G01X1011024D01*
G02X1018898Y134331I0J-7874D01*
G01Y54252D01*
G03X1026772Y46378I7874J0D01*
G01X1518118D01*
G02X1525992Y38504I0J-7874D01*
G01Y1969D01*
G03X1527961Y0I1969J0D01*
G01X1794102D01*
G03X1796071Y1969I0J1969D01*
G01Y38504D01*
G02X1803945Y46378I7874J0D01*
G01X1849606D01*
G03X1857480Y54252I0J7874D01*
G01X2306Y311361D02*
G03X0Y305794I5567J-5567D01*
G01Y54252D01*
G03X7874Y46378I7874J0D01*
G01X43709D01*
G02X51583Y38504I0J-7874D01*
G01Y1969D01*
G03X53551Y0I1968J0D01*
G01X319693D01*
G03X321661Y1969I0J1969D01*
G01Y38504D01*
G02X329535Y46378I7874J0D01*
G01X488591D01*
G02X496465Y38504I0J-7874D01*
G01Y22756D01*
G03X498433Y20787I1968J-1D01*
G01X764575D01*
G03X766543Y22756I-1J1969D01*
G01Y38504D01*
G02X774417Y46378I7874J0D01*
G01X871260D01*
G03X879134Y54252I0J7874D01*
G01Y134331D01*
G02X887008Y142205I7874J0D01*
G01X1011024D01*
G02X1018898Y134331I0J-7874D01*
G01Y54252D01*
G03X1026772Y46378I7874J0D01*
G01X1518118D01*
G02X1525992Y38504I0J-7874D01*
G01Y1969D01*
G03X1527961Y0I1969J0D01*
G01X1794102D01*
G03X1796071Y1969I0J1969D01*
G01Y38504D01*
G02X1803945Y46378I7874J0D01*
G01X1849606D01*
G03X1857480Y54252I0J7874D01*
G01Y305794D01*
G01X2306Y311361D02*
G03X0Y305794I5567J-5567D01*
G01Y54252D01*
G03X7874Y46378I7874J0D01*
G01X43709D01*
G02X51583Y38504I0J-7874D01*
G01Y1969D01*
G03X53551Y0I1968J0D01*
G01X319693D01*
G03X321661Y1969I0J1969D01*
G01Y38504D01*
G02X329535Y46378I7874J0D01*
G01X488591D01*
G02X496465Y38504I0J-7874D01*
G01Y22756D01*
G03X498433Y20787I1968J-1D01*
G01X764575D01*
G03X766543Y22756I-1J1969D01*
G01Y38504D01*
G02X774417Y46378I7874J0D01*
G01X871260D01*
G03X879134Y54252I0J7874D01*
G01Y134331D01*
G02X887008Y142205I7874J0D01*
G01X1011024D01*
G02X1018898Y134331I0J-7874D01*
G01Y54252D01*
G03X1026772Y46378I7874J0D01*
G01X1518118D01*
G02X1525992Y38504I0J-7874D01*
G01Y1969D01*
G03X1527961Y0I1969J0D01*
G01X1794102D01*
G03X1796071Y1969I0J1969D01*
G01Y38504D01*
G02X1803945Y46378I7874J0D01*
G01X1849606D01*
G03X1857480Y54252I0J7874D01*
G01Y305794D01*
G03X1855174Y311361I-7873J0D01*
G01X2306D02*
G03X0Y305794I5567J-5567D01*
G01Y54252D01*
G03X7874Y46378I7874J0D01*
G01X43709D01*
G02X51583Y38504I0J-7874D01*
G01Y1969D01*
G03X53551Y0I1968J0D01*
G01X319693D01*
G03X321661Y1969I0J1969D01*
G01Y38504D01*
G02X329535Y46378I7874J0D01*
G01X488591D01*
G02X496465Y38504I0J-7874D01*
G01Y22756D01*
G03X498433Y20787I1968J-1D01*
G01X764575D01*
G03X766543Y22756I-1J1969D01*
G01Y38504D01*
G02X774417Y46378I7874J0D01*
G01X871260D01*
G03X879134Y54252I0J7874D01*
G01Y134331D01*
G02X887008Y142205I7874J0D01*
G01X1011024D01*
G02X1018898Y134331I0J-7874D01*
G01Y54252D01*
G03X1026772Y46378I7874J0D01*
G01X1518118D01*
G02X1525992Y38504I0J-7874D01*
G01Y1969D01*
G03X1527961Y0I1969J0D01*
G01X1794102D01*
G03X1796071Y1969I0J1969D01*
G01Y38504D01*
G02X1803945Y46378I7874J0D01*
G01X1849606D01*
G03X1857480Y54252I0J7874D01*
G01Y305794D01*
G03X1855174Y311361I-7873J0D01*
G01X1846007Y320528D01*
G01X2306Y311361D02*
G03X0Y305794I5567J-5567D01*
G01Y54252D01*
G03X7874Y46378I7874J0D01*
G01X43709D01*
G02X51583Y38504I0J-7874D01*
G01Y1969D01*
G03X53551Y0I1968J0D01*
G01X319693D01*
G03X321661Y1969I0J1969D01*
G01Y38504D01*
G02X329535Y46378I7874J0D01*
G01X488591D01*
G02X496465Y38504I0J-7874D01*
G01Y22756D01*
G03X498433Y20787I1968J-1D01*
G01X764575D01*
G03X766543Y22756I-1J1969D01*
G01Y38504D01*
G02X774417Y46378I7874J0D01*
G01X871260D01*
G03X879134Y54252I0J7874D01*
G01Y134331D01*
G02X887008Y142205I7874J0D01*
G01X1011024D01*
G02X1018898Y134331I0J-7874D01*
G01Y54252D01*
G03X1026772Y46378I7874J0D01*
G01X1518118D01*
G02X1525992Y38504I0J-7874D01*
G01Y1969D01*
G03X1527961Y0I1969J0D01*
G01X1794102D01*
G03X1796071Y1969I0J1969D01*
G01Y38504D01*
G02X1803945Y46378I7874J0D01*
G01X1849606D01*
G03X1857480Y54252I0J7874D01*
G01Y305794D01*
G03X1855174Y311361I-7873J0D01*
G01X1846007Y320528D01*
G02X1843701Y326096I5568J5568D01*
G01X2306Y311361D02*
G03X0Y305794I5567J-5567D01*
G01Y54252D01*
G03X7874Y46378I7874J0D01*
G01X43709D01*
G02X51583Y38504I0J-7874D01*
G01Y1969D01*
G03X53551Y0I1968J0D01*
G01X319693D01*
G03X321661Y1969I0J1969D01*
G01Y38504D01*
G02X329535Y46378I7874J0D01*
G01X488591D01*
G02X496465Y38504I0J-7874D01*
G01Y22756D01*
G03X498433Y20787I1968J-1D01*
G01X764575D01*
G03X766543Y22756I-1J1969D01*
G01Y38504D01*
G02X774417Y46378I7874J0D01*
G01X871260D01*
G03X879134Y54252I0J7874D01*
G01Y134331D01*
G02X887008Y142205I7874J0D01*
G01X1011024D01*
G02X1018898Y134331I0J-7874D01*
G01Y54252D01*
G03X1026772Y46378I7874J0D01*
G01X1518118D01*
G02X1525992Y38504I0J-7874D01*
G01Y1969D01*
G03X1527961Y0I1969J0D01*
G01X1794102D01*
G03X1796071Y1969I0J1969D01*
G01Y38504D01*
G02X1803945Y46378I7874J0D01*
G01X1849606D01*
G03X1857480Y54252I0J7874D01*
G01Y305794D01*
G03X1855174Y311361I-7873J0D01*
G01X1846007Y320528D01*
G02X1843701Y326096I5568J5568D01*
G01Y1593983D01*
G01X2306Y311361D02*
G03X0Y305794I5567J-5567D01*
G01Y54252D01*
G03X7874Y46378I7874J0D01*
G01X43709D01*
G02X51583Y38504I0J-7874D01*
G01Y1969D01*
G03X53551Y0I1968J0D01*
G01X319693D01*
G03X321661Y1969I0J1969D01*
G01Y38504D01*
G02X329535Y46378I7874J0D01*
G01X488591D01*
G02X496465Y38504I0J-7874D01*
G01Y22756D01*
G03X498433Y20787I1968J-1D01*
G01X764575D01*
G03X766543Y22756I-1J1969D01*
G01Y38504D01*
G02X774417Y46378I7874J0D01*
G01X871260D01*
G03X879134Y54252I0J7874D01*
G01Y134331D01*
G02X887008Y142205I7874J0D01*
G01X1011024D01*
G02X1018898Y134331I0J-7874D01*
G01Y54252D01*
G03X1026772Y46378I7874J0D01*
G01X1518118D01*
G02X1525992Y38504I0J-7874D01*
G01Y1969D01*
G03X1527961Y0I1969J0D01*
G01X1794102D01*
G03X1796071Y1969I0J1969D01*
G01Y38504D01*
G02X1803945Y46378I7874J0D01*
G01X1849606D01*
G03X1857480Y54252I0J7874D01*
G01Y305794D01*
G03X1855174Y311361I-7873J0D01*
G01X1846007Y320528D01*
G02X1843701Y326096I5568J5568D01*
G01Y1593983D01*
G03X1841395Y1599550I-7873J0D01*
G01X2306Y311361D02*
G03X0Y305794I5567J-5567D01*
G01Y54252D01*
G03X7874Y46378I7874J0D01*
G01X43709D01*
G02X51583Y38504I0J-7874D01*
G01Y1969D01*
G03X53551Y0I1968J0D01*
G01X319693D01*
G03X321661Y1969I0J1969D01*
G01Y38504D01*
G02X329535Y46378I7874J0D01*
G01X488591D01*
G02X496465Y38504I0J-7874D01*
G01Y22756D01*
G03X498433Y20787I1968J-1D01*
G01X764575D01*
G03X766543Y22756I-1J1969D01*
G01Y38504D01*
G02X774417Y46378I7874J0D01*
G01X871260D01*
G03X879134Y54252I0J7874D01*
G01Y134331D01*
G02X887008Y142205I7874J0D01*
G01X1011024D01*
G02X1018898Y134331I0J-7874D01*
G01Y54252D01*
G03X1026772Y46378I7874J0D01*
G01X1518118D01*
G02X1525992Y38504I0J-7874D01*
G01Y1969D01*
G03X1527961Y0I1969J0D01*
G01X1794102D01*
G03X1796071Y1969I0J1969D01*
G01Y38504D01*
G02X1803945Y46378I7874J0D01*
G01X1849606D01*
G03X1857480Y54252I0J7874D01*
G01Y305794D01*
G03X1855174Y311361I-7873J0D01*
G01X1846007Y320528D01*
G02X1843701Y326096I5568J5568D01*
G01Y1593983D01*
G03X1841395Y1599550I-7873J0D01*
G01X1834196Y1606749D01*
G01X2306Y311361D02*
G03X0Y305794I5567J-5567D01*
G01Y54252D01*
G03X7874Y46378I7874J0D01*
G01X43709D01*
G02X51583Y38504I0J-7874D01*
G01Y1969D01*
G03X53551Y0I1968J0D01*
G01X319693D01*
G03X321661Y1969I0J1969D01*
G01Y38504D01*
G02X329535Y46378I7874J0D01*
G01X488591D01*
G02X496465Y38504I0J-7874D01*
G01Y22756D01*
G03X498433Y20787I1968J-1D01*
G01X764575D01*
G03X766543Y22756I-1J1969D01*
G01Y38504D01*
G02X774417Y46378I7874J0D01*
G01X871260D01*
G03X879134Y54252I0J7874D01*
G01Y134331D01*
G02X887008Y142205I7874J0D01*
G01X1011024D01*
G02X1018898Y134331I0J-7874D01*
G01Y54252D01*
G03X1026772Y46378I7874J0D01*
G01X1518118D01*
G02X1525992Y38504I0J-7874D01*
G01Y1969D01*
G03X1527961Y0I1969J0D01*
G01X1794102D01*
G03X1796071Y1969I0J1969D01*
G01Y38504D01*
G02X1803945Y46378I7874J0D01*
G01X1849606D01*
G03X1857480Y54252I0J7874D01*
G01Y305794D01*
G03X1855174Y311361I-7873J0D01*
G01X1846007Y320528D01*
G02X1843701Y326096I5568J5568D01*
G01Y1593983D01*
G03X1841395Y1599550I-7873J0D01*
G01X1834196Y1606749D01*
G02X1831890Y1612317I5568J5568D01*
G01X2306Y311361D02*
G03X0Y305794I5567J-5567D01*
G01Y54252D01*
G03X7874Y46378I7874J0D01*
G01X43709D01*
G02X51583Y38504I0J-7874D01*
G01Y1969D01*
G03X53551Y0I1968J0D01*
G01X319693D01*
G03X321661Y1969I0J1969D01*
G01Y38504D01*
G02X329535Y46378I7874J0D01*
G01X488591D01*
G02X496465Y38504I0J-7874D01*
G01Y22756D01*
G03X498433Y20787I1968J-1D01*
G01X764575D01*
G03X766543Y22756I-1J1969D01*
G01Y38504D01*
G02X774417Y46378I7874J0D01*
G01X871260D01*
G03X879134Y54252I0J7874D01*
G01Y134331D01*
G02X887008Y142205I7874J0D01*
G01X1011024D01*
G02X1018898Y134331I0J-7874D01*
G01Y54252D01*
G03X1026772Y46378I7874J0D01*
G01X1518118D01*
G02X1525992Y38504I0J-7874D01*
G01Y1969D01*
G03X1527961Y0I1969J0D01*
G01X1794102D01*
G03X1796071Y1969I0J1969D01*
G01Y38504D01*
G02X1803945Y46378I7874J0D01*
G01X1849606D01*
G03X1857480Y54252I0J7874D01*
G01Y305794D01*
G03X1855174Y311361I-7873J0D01*
G01X1846007Y320528D01*
G02X1843701Y326096I5568J5568D01*
G01Y1593983D01*
G03X1841395Y1599550I-7873J0D01*
G01X1834196Y1606749D01*
G02X1831890Y1612317I5568J5568D01*
G01Y1732244D01*
G01X2306Y311361D02*
G03X0Y305794I5567J-5567D01*
G01Y54252D01*
G03X7874Y46378I7874J0D01*
G01X43709D01*
G02X51583Y38504I0J-7874D01*
G01Y1969D01*
G03X53551Y0I1968J0D01*
G01X319693D01*
G03X321661Y1969I0J1969D01*
G01Y38504D01*
G02X329535Y46378I7874J0D01*
G01X488591D01*
G02X496465Y38504I0J-7874D01*
G01Y22756D01*
G03X498433Y20787I1968J-1D01*
G01X764575D01*
G03X766543Y22756I-1J1969D01*
G01Y38504D01*
G02X774417Y46378I7874J0D01*
G01X871260D01*
G03X879134Y54252I0J7874D01*
G01Y134331D01*
G02X887008Y142205I7874J0D01*
G01X1011024D01*
G02X1018898Y134331I0J-7874D01*
G01Y54252D01*
G03X1026772Y46378I7874J0D01*
G01X1518118D01*
G02X1525992Y38504I0J-7874D01*
G01Y1969D01*
G03X1527961Y0I1969J0D01*
G01X1794102D01*
G03X1796071Y1969I0J1969D01*
G01Y38504D01*
G02X1803945Y46378I7874J0D01*
G01X1849606D01*
G03X1857480Y54252I0J7874D01*
G01Y305794D01*
G03X1855174Y311361I-7873J0D01*
G01X1846007Y320528D01*
G02X1843701Y326096I5568J5568D01*
G01Y1593983D01*
G03X1841395Y1599550I-7873J0D01*
G01X1834196Y1606749D01*
G02X1831890Y1612317I5568J5568D01*
G01Y1732244D01*
G03X1824016Y1740118I-7874J0D01*
G01X2306Y311361D02*
G03X0Y305794I5567J-5567D01*
G01Y54252D01*
G03X7874Y46378I7874J0D01*
G01X43709D01*
G02X51583Y38504I0J-7874D01*
G01Y1969D01*
G03X53551Y0I1968J0D01*
G01X319693D01*
G03X321661Y1969I0J1969D01*
G01Y38504D01*
G02X329535Y46378I7874J0D01*
G01X488591D01*
G02X496465Y38504I0J-7874D01*
G01Y22756D01*
G03X498433Y20787I1968J-1D01*
G01X764575D01*
G03X766543Y22756I-1J1969D01*
G01Y38504D01*
G02X774417Y46378I7874J0D01*
G01X871260D01*
G03X879134Y54252I0J7874D01*
G01Y134331D01*
G02X887008Y142205I7874J0D01*
G01X1011024D01*
G02X1018898Y134331I0J-7874D01*
G01Y54252D01*
G03X1026772Y46378I7874J0D01*
G01X1518118D01*
G02X1525992Y38504I0J-7874D01*
G01Y1969D01*
G03X1527961Y0I1969J0D01*
G01X1794102D01*
G03X1796071Y1969I0J1969D01*
G01Y38504D01*
G02X1803945Y46378I7874J0D01*
G01X1849606D01*
G03X1857480Y54252I0J7874D01*
G01Y305794D01*
G03X1855174Y311361I-7873J0D01*
G01X1846007Y320528D01*
G02X1843701Y326096I5568J5568D01*
G01Y1593983D01*
G03X1841395Y1599550I-7873J0D01*
G01X1834196Y1606749D01*
G02X1831890Y1612317I5568J5568D01*
G01Y1732244D01*
G03X1824016Y1740118I-7874J0D01*
G01X1091791D01*
G01X2306Y311361D02*
G03X0Y305794I5567J-5567D01*
G01Y54252D01*
G03X7874Y46378I7874J0D01*
G01X43709D01*
G02X51583Y38504I0J-7874D01*
G01Y1969D01*
G03X53551Y0I1968J0D01*
G01X319693D01*
G03X321661Y1969I0J1969D01*
G01Y38504D01*
G02X329535Y46378I7874J0D01*
G01X488591D01*
G02X496465Y38504I0J-7874D01*
G01Y22756D01*
G03X498433Y20787I1968J-1D01*
G01X764575D01*
G03X766543Y22756I-1J1969D01*
G01Y38504D01*
G02X774417Y46378I7874J0D01*
G01X871260D01*
G03X879134Y54252I0J7874D01*
G01Y134331D01*
G02X887008Y142205I7874J0D01*
G01X1011024D01*
G02X1018898Y134331I0J-7874D01*
G01Y54252D01*
G03X1026772Y46378I7874J0D01*
G01X1518118D01*
G02X1525992Y38504I0J-7874D01*
G01Y1969D01*
G03X1527961Y0I1969J0D01*
G01X1794102D01*
G03X1796071Y1969I0J1969D01*
G01Y38504D01*
G02X1803945Y46378I7874J0D01*
G01X1849606D01*
G03X1857480Y54252I0J7874D01*
G01Y305794D01*
G03X1855174Y311361I-7873J0D01*
G01X1846007Y320528D01*
G02X1843701Y326096I5568J5568D01*
G01Y1593983D01*
G03X1841395Y1599550I-7873J0D01*
G01X1834196Y1606749D01*
G02X1831890Y1612317I5568J5568D01*
G01Y1732244D01*
G03X1824016Y1740118I-7874J0D01*
G01X1091791D01*
G03X1089823Y1738150I0J-1968D01*
G01X2306Y311361D02*
G03X0Y305794I5567J-5567D01*
G01Y54252D01*
G03X7874Y46378I7874J0D01*
G01X43709D01*
G02X51583Y38504I0J-7874D01*
G01Y1969D01*
G03X53551Y0I1968J0D01*
G01X319693D01*
G03X321661Y1969I0J1969D01*
G01Y38504D01*
G02X329535Y46378I7874J0D01*
G01X488591D01*
G02X496465Y38504I0J-7874D01*
G01Y22756D01*
G03X498433Y20787I1968J-1D01*
G01X764575D01*
G03X766543Y22756I-1J1969D01*
G01Y38504D01*
G02X774417Y46378I7874J0D01*
G01X871260D01*
G03X879134Y54252I0J7874D01*
G01Y134331D01*
G02X887008Y142205I7874J0D01*
G01X1011024D01*
G02X1018898Y134331I0J-7874D01*
G01Y54252D01*
G03X1026772Y46378I7874J0D01*
G01X1518118D01*
G02X1525992Y38504I0J-7874D01*
G01Y1969D01*
G03X1527961Y0I1969J0D01*
G01X1794102D01*
G03X1796071Y1969I0J1969D01*
G01Y38504D01*
G02X1803945Y46378I7874J0D01*
G01X1849606D01*
G03X1857480Y54252I0J7874D01*
G01Y305794D01*
G03X1855174Y311361I-7873J0D01*
G01X1846007Y320528D01*
G02X1843701Y326096I5568J5568D01*
G01Y1593983D01*
G03X1841395Y1599550I-7873J0D01*
G01X1834196Y1606749D01*
G02X1831890Y1612317I5568J5568D01*
G01Y1732244D01*
G03X1824016Y1740118I-7874J0D01*
G01X1091791D01*
G03X1089823Y1738150I0J-1968D01*
G01Y1736890D01*
G01X2306Y311361D02*
G03X0Y305794I5567J-5567D01*
G01Y54252D01*
G03X7874Y46378I7874J0D01*
G01X43709D01*
G02X51583Y38504I0J-7874D01*
G01Y1969D01*
G03X53551Y0I1968J0D01*
G01X319693D01*
G03X321661Y1969I0J1969D01*
G01Y38504D01*
G02X329535Y46378I7874J0D01*
G01X488591D01*
G02X496465Y38504I0J-7874D01*
G01Y22756D01*
G03X498433Y20787I1968J-1D01*
G01X764575D01*
G03X766543Y22756I-1J1969D01*
G01Y38504D01*
G02X774417Y46378I7874J0D01*
G01X871260D01*
G03X879134Y54252I0J7874D01*
G01Y134331D01*
G02X887008Y142205I7874J0D01*
G01X1011024D01*
G02X1018898Y134331I0J-7874D01*
G01Y54252D01*
G03X1026772Y46378I7874J0D01*
G01X1518118D01*
G02X1525992Y38504I0J-7874D01*
G01Y1969D01*
G03X1527961Y0I1969J0D01*
G01X1794102D01*
G03X1796071Y1969I0J1969D01*
G01Y38504D01*
G02X1803945Y46378I7874J0D01*
G01X1849606D01*
G03X1857480Y54252I0J7874D01*
G01Y305794D01*
G03X1855174Y311361I-7873J0D01*
G01X1846007Y320528D01*
G02X1843701Y326096I5568J5568D01*
G01Y1593983D01*
G03X1841395Y1599550I-7873J0D01*
G01X1834196Y1606749D01*
G02X1831890Y1612317I5568J5568D01*
G01Y1732244D01*
G03X1824016Y1740118I-7874J0D01*
G01X1091791D01*
G03X1089823Y1738150I0J-1968D01*
G01Y1736890D01*
G02X1087854Y1734921I-1969J0D01*
G01X2306Y311361D02*
G03X0Y305794I5567J-5567D01*
G01Y54252D01*
G03X7874Y46378I7874J0D01*
G01X43709D01*
G02X51583Y38504I0J-7874D01*
G01Y1969D01*
G03X53551Y0I1968J0D01*
G01X319693D01*
G03X321661Y1969I0J1969D01*
G01Y38504D01*
G02X329535Y46378I7874J0D01*
G01X488591D01*
G02X496465Y38504I0J-7874D01*
G01Y22756D01*
G03X498433Y20787I1968J-1D01*
G01X764575D01*
G03X766543Y22756I-1J1969D01*
G01Y38504D01*
G02X774417Y46378I7874J0D01*
G01X871260D01*
G03X879134Y54252I0J7874D01*
G01Y134331D01*
G02X887008Y142205I7874J0D01*
G01X1011024D01*
G02X1018898Y134331I0J-7874D01*
G01Y54252D01*
G03X1026772Y46378I7874J0D01*
G01X1518118D01*
G02X1525992Y38504I0J-7874D01*
G01Y1969D01*
G03X1527961Y0I1969J0D01*
G01X1794102D01*
G03X1796071Y1969I0J1969D01*
G01Y38504D01*
G02X1803945Y46378I7874J0D01*
G01X1849606D01*
G03X1857480Y54252I0J7874D01*
G01Y305794D01*
G03X1855174Y311361I-7873J0D01*
G01X1846007Y320528D01*
G02X1843701Y326096I5568J5568D01*
G01Y1593983D01*
G03X1841395Y1599550I-7873J0D01*
G01X1834196Y1606749D01*
G02X1831890Y1612317I5568J5568D01*
G01Y1732244D01*
G03X1824016Y1740118I-7874J0D01*
G01X1091791D01*
G03X1089823Y1738150I0J-1968D01*
G01Y1736890D01*
G02X1087854Y1734921I-1969J0D01*
G01X769705D01*
G01X2306Y311361D02*
G03X0Y305794I5567J-5567D01*
G01Y54252D01*
G03X7874Y46378I7874J0D01*
G01X43709D01*
G02X51583Y38504I0J-7874D01*
G01Y1969D01*
G03X53551Y0I1968J0D01*
G01X319693D01*
G03X321661Y1969I0J1969D01*
G01Y38504D01*
G02X329535Y46378I7874J0D01*
G01X488591D01*
G02X496465Y38504I0J-7874D01*
G01Y22756D01*
G03X498433Y20787I1968J-1D01*
G01X764575D01*
G03X766543Y22756I-1J1969D01*
G01Y38504D01*
G02X774417Y46378I7874J0D01*
G01X871260D01*
G03X879134Y54252I0J7874D01*
G01Y134331D01*
G02X887008Y142205I7874J0D01*
G01X1011024D01*
G02X1018898Y134331I0J-7874D01*
G01Y54252D01*
G03X1026772Y46378I7874J0D01*
G01X1518118D01*
G02X1525992Y38504I0J-7874D01*
G01Y1969D01*
G03X1527961Y0I1969J0D01*
G01X1794102D01*
G03X1796071Y1969I0J1969D01*
G01Y38504D01*
G02X1803945Y46378I7874J0D01*
G01X1849606D01*
G03X1857480Y54252I0J7874D01*
G01Y305794D01*
G03X1855174Y311361I-7873J0D01*
G01X1846007Y320528D01*
G02X1843701Y326096I5568J5568D01*
G01Y1593983D01*
G03X1841395Y1599550I-7873J0D01*
G01X1834196Y1606749D01*
G02X1831890Y1612317I5568J5568D01*
G01Y1732244D01*
G03X1824016Y1740118I-7874J0D01*
G01X1091791D01*
G03X1089823Y1738150I0J-1968D01*
G01Y1736890D01*
G02X1087854Y1734921I-1969J0D01*
G01X769705D01*
G02X767736Y1736890I0J1969D01*
G01X2306Y311361D02*
G03X0Y305794I5567J-5567D01*
G01Y54252D01*
G03X7874Y46378I7874J0D01*
G01X43709D01*
G02X51583Y38504I0J-7874D01*
G01Y1969D01*
G03X53551Y0I1968J0D01*
G01X319693D01*
G03X321661Y1969I0J1969D01*
G01Y38504D01*
G02X329535Y46378I7874J0D01*
G01X488591D01*
G02X496465Y38504I0J-7874D01*
G01Y22756D01*
G03X498433Y20787I1968J-1D01*
G01X764575D01*
G03X766543Y22756I-1J1969D01*
G01Y38504D01*
G02X774417Y46378I7874J0D01*
G01X871260D01*
G03X879134Y54252I0J7874D01*
G01Y134331D01*
G02X887008Y142205I7874J0D01*
G01X1011024D01*
G02X1018898Y134331I0J-7874D01*
G01Y54252D01*
G03X1026772Y46378I7874J0D01*
G01X1518118D01*
G02X1525992Y38504I0J-7874D01*
G01Y1969D01*
G03X1527961Y0I1969J0D01*
G01X1794102D01*
G03X1796071Y1969I0J1969D01*
G01Y38504D01*
G02X1803945Y46378I7874J0D01*
G01X1849606D01*
G03X1857480Y54252I0J7874D01*
G01Y305794D01*
G03X1855174Y311361I-7873J0D01*
G01X1846007Y320528D01*
G02X1843701Y326096I5568J5568D01*
G01Y1593983D01*
G03X1841395Y1599550I-7873J0D01*
G01X1834196Y1606749D01*
G02X1831890Y1612317I5568J5568D01*
G01Y1732244D01*
G03X1824016Y1740118I-7874J0D01*
G01X1091791D01*
G03X1089823Y1738150I0J-1968D01*
G01Y1736890D01*
G02X1087854Y1734921I-1969J0D01*
G01X769705D01*
G02X767736Y1736890I0J1969D01*
G01Y1738150D01*
G01X2306Y311361D02*
G03X0Y305794I5567J-5567D01*
G01Y54252D01*
G03X7874Y46378I7874J0D01*
G01X43709D01*
G02X51583Y38504I0J-7874D01*
G01Y1969D01*
G03X53551Y0I1968J0D01*
G01X319693D01*
G03X321661Y1969I0J1969D01*
G01Y38504D01*
G02X329535Y46378I7874J0D01*
G01X488591D01*
G02X496465Y38504I0J-7874D01*
G01Y22756D01*
G03X498433Y20787I1968J-1D01*
G01X764575D01*
G03X766543Y22756I-1J1969D01*
G01Y38504D01*
G02X774417Y46378I7874J0D01*
G01X871260D01*
G03X879134Y54252I0J7874D01*
G01Y134331D01*
G02X887008Y142205I7874J0D01*
G01X1011024D01*
G02X1018898Y134331I0J-7874D01*
G01Y54252D01*
G03X1026772Y46378I7874J0D01*
G01X1518118D01*
G02X1525992Y38504I0J-7874D01*
G01Y1969D01*
G03X1527961Y0I1969J0D01*
G01X1794102D01*
G03X1796071Y1969I0J1969D01*
G01Y38504D01*
G02X1803945Y46378I7874J0D01*
G01X1849606D01*
G03X1857480Y54252I0J7874D01*
G01Y305794D01*
G03X1855174Y311361I-7873J0D01*
G01X1846007Y320528D01*
G02X1843701Y326096I5568J5568D01*
G01Y1593983D01*
G03X1841395Y1599550I-7873J0D01*
G01X1834196Y1606749D01*
G02X1831890Y1612317I5568J5568D01*
G01Y1732244D01*
G03X1824016Y1740118I-7874J0D01*
G01X1091791D01*
G03X1089823Y1738150I0J-1968D01*
G01Y1736890D01*
G02X1087854Y1734921I-1969J0D01*
G01X769705D01*
G02X767736Y1736890I0J1969D01*
G01Y1738150D01*
G03X765768Y1740118I-1968J0D01*
G01X2306Y311361D02*
G03X0Y305794I5567J-5567D01*
G01Y54252D01*
G03X7874Y46378I7874J0D01*
G01X43709D01*
G02X51583Y38504I0J-7874D01*
G01Y1969D01*
G03X53551Y0I1968J0D01*
G01X319693D01*
G03X321661Y1969I0J1969D01*
G01Y38504D01*
G02X329535Y46378I7874J0D01*
G01X488591D01*
G02X496465Y38504I0J-7874D01*
G01Y22756D01*
G03X498433Y20787I1968J-1D01*
G01X764575D01*
G03X766543Y22756I-1J1969D01*
G01Y38504D01*
G02X774417Y46378I7874J0D01*
G01X871260D01*
G03X879134Y54252I0J7874D01*
G01Y134331D01*
G02X887008Y142205I7874J0D01*
G01X1011024D01*
G02X1018898Y134331I0J-7874D01*
G01Y54252D01*
G03X1026772Y46378I7874J0D01*
G01X1518118D01*
G02X1525992Y38504I0J-7874D01*
G01Y1969D01*
G03X1527961Y0I1969J0D01*
G01X1794102D01*
G03X1796071Y1969I0J1969D01*
G01Y38504D01*
G02X1803945Y46378I7874J0D01*
G01X1849606D01*
G03X1857480Y54252I0J7874D01*
G01Y305794D01*
G03X1855174Y311361I-7873J0D01*
G01X1846007Y320528D01*
G02X1843701Y326096I5568J5568D01*
G01Y1593983D01*
G03X1841395Y1599550I-7873J0D01*
G01X1834196Y1606749D01*
G02X1831890Y1612317I5568J5568D01*
G01Y1732244D01*
G03X1824016Y1740118I-7874J0D01*
G01X1091791D01*
G03X1089823Y1738150I0J-1968D01*
G01Y1736890D01*
G02X1087854Y1734921I-1969J0D01*
G01X769705D01*
G02X767736Y1736890I0J1969D01*
G01Y1738150D01*
G03X765768Y1740118I-1968J0D01*
G01X33465D01*
G01X2306Y311361D02*
G03X0Y305794I5567J-5567D01*
G01Y54252D01*
G03X7874Y46378I7874J0D01*
G01X43709D01*
G02X51583Y38504I0J-7874D01*
G01Y1969D01*
G03X53551Y0I1968J0D01*
G01X319693D01*
G03X321661Y1969I0J1969D01*
G01Y38504D01*
G02X329535Y46378I7874J0D01*
G01X488591D01*
G02X496465Y38504I0J-7874D01*
G01Y22756D01*
G03X498433Y20787I1968J-1D01*
G01X764575D01*
G03X766543Y22756I-1J1969D01*
G01Y38504D01*
G02X774417Y46378I7874J0D01*
G01X871260D01*
G03X879134Y54252I0J7874D01*
G01Y134331D01*
G02X887008Y142205I7874J0D01*
G01X1011024D01*
G02X1018898Y134331I0J-7874D01*
G01Y54252D01*
G03X1026772Y46378I7874J0D01*
G01X1518118D01*
G02X1525992Y38504I0J-7874D01*
G01Y1969D01*
G03X1527961Y0I1969J0D01*
G01X1794102D01*
G03X1796071Y1969I0J1969D01*
G01Y38504D01*
G02X1803945Y46378I7874J0D01*
G01X1849606D01*
G03X1857480Y54252I0J7874D01*
G01Y305794D01*
G03X1855174Y311361I-7873J0D01*
G01X1846007Y320528D01*
G02X1843701Y326096I5568J5568D01*
G01Y1593983D01*
G03X1841395Y1599550I-7873J0D01*
G01X1834196Y1606749D01*
G02X1831890Y1612317I5568J5568D01*
G01Y1732244D01*
G03X1824016Y1740118I-7874J0D01*
G01X1091791D01*
G03X1089823Y1738150I0J-1968D01*
G01Y1736890D01*
G02X1087854Y1734921I-1969J0D01*
G01X769705D01*
G02X767736Y1736890I0J1969D01*
G01Y1738150D01*
G03X765768Y1740118I-1968J0D01*
G01X33465D01*
G03X25591Y1732244I0J-7874D01*
G01X2306Y311361D02*
G03X0Y305794I5567J-5567D01*
G01Y54252D01*
G03X7874Y46378I7874J0D01*
G01X43709D01*
G02X51583Y38504I0J-7874D01*
G01Y1969D01*
G03X53551Y0I1968J0D01*
G01X319693D01*
G03X321661Y1969I0J1969D01*
G01Y38504D01*
G02X329535Y46378I7874J0D01*
G01X488591D01*
G02X496465Y38504I0J-7874D01*
G01Y22756D01*
G03X498433Y20787I1968J-1D01*
G01X764575D01*
G03X766543Y22756I-1J1969D01*
G01Y38504D01*
G02X774417Y46378I7874J0D01*
G01X871260D01*
G03X879134Y54252I0J7874D01*
G01Y134331D01*
G02X887008Y142205I7874J0D01*
G01X1011024D01*
G02X1018898Y134331I0J-7874D01*
G01Y54252D01*
G03X1026772Y46378I7874J0D01*
G01X1518118D01*
G02X1525992Y38504I0J-7874D01*
G01Y1969D01*
G03X1527961Y0I1969J0D01*
G01X1794102D01*
G03X1796071Y1969I0J1969D01*
G01Y38504D01*
G02X1803945Y46378I7874J0D01*
G01X1849606D01*
G03X1857480Y54252I0J7874D01*
G01Y305794D01*
G03X1855174Y311361I-7873J0D01*
G01X1846007Y320528D01*
G02X1843701Y326096I5568J5568D01*
G01Y1593983D01*
G03X1841395Y1599550I-7873J0D01*
G01X1834196Y1606749D01*
G02X1831890Y1612317I5568J5568D01*
G01Y1732244D01*
G03X1824016Y1740118I-7874J0D01*
G01X1091791D01*
G03X1089823Y1738150I0J-1968D01*
G01Y1736890D01*
G02X1087854Y1734921I-1969J0D01*
G01X769705D01*
G02X767736Y1736890I0J1969D01*
G01Y1738150D01*
G03X765768Y1740118I-1968J0D01*
G01X33465D01*
G03X25591Y1732244I0J-7874D01*
G01Y1612317D01*
G01X2306Y311361D02*
G03X0Y305794I5567J-5567D01*
G01Y54252D01*
G03X7874Y46378I7874J0D01*
G01X43709D01*
G02X51583Y38504I0J-7874D01*
G01Y1969D01*
G03X53551Y0I1968J0D01*
G01X319693D01*
G03X321661Y1969I0J1969D01*
G01Y38504D01*
G02X329535Y46378I7874J0D01*
G01X488591D01*
G02X496465Y38504I0J-7874D01*
G01Y22756D01*
G03X498433Y20787I1968J-1D01*
G01X764575D01*
G03X766543Y22756I-1J1969D01*
G01Y38504D01*
G02X774417Y46378I7874J0D01*
G01X871260D01*
G03X879134Y54252I0J7874D01*
G01Y134331D01*
G02X887008Y142205I7874J0D01*
G01X1011024D01*
G02X1018898Y134331I0J-7874D01*
G01Y54252D01*
G03X1026772Y46378I7874J0D01*
G01X1518118D01*
G02X1525992Y38504I0J-7874D01*
G01Y1969D01*
G03X1527961Y0I1969J0D01*
G01X1794102D01*
G03X1796071Y1969I0J1969D01*
G01Y38504D01*
G02X1803945Y46378I7874J0D01*
G01X1849606D01*
G03X1857480Y54252I0J7874D01*
G01Y305794D01*
G03X1855174Y311361I-7873J0D01*
G01X1846007Y320528D01*
G02X1843701Y326096I5568J5568D01*
G01Y1593983D01*
G03X1841395Y1599550I-7873J0D01*
G01X1834196Y1606749D01*
G02X1831890Y1612317I5568J5568D01*
G01Y1732244D01*
G03X1824016Y1740118I-7874J0D01*
G01X1091791D01*
G03X1089823Y1738150I0J-1968D01*
G01Y1736890D01*
G02X1087854Y1734921I-1969J0D01*
G01X769705D01*
G02X767736Y1736890I0J1969D01*
G01Y1738150D01*
G03X765768Y1740118I-1968J0D01*
G01X33465D01*
G03X25591Y1732244I0J-7874D01*
G01Y1612317D01*
G02X23284Y1606749I-7875J1D01*
G01X2306Y311361D02*
G03X0Y305794I5567J-5567D01*
G01Y54252D01*
G03X7874Y46378I7874J0D01*
G01X43709D01*
G02X51583Y38504I0J-7874D01*
G01Y1969D01*
G03X53551Y0I1968J0D01*
G01X319693D01*
G03X321661Y1969I0J1969D01*
G01Y38504D01*
G02X329535Y46378I7874J0D01*
G01X488591D01*
G02X496465Y38504I0J-7874D01*
G01Y22756D01*
G03X498433Y20787I1968J-1D01*
G01X764575D01*
G03X766543Y22756I-1J1969D01*
G01Y38504D01*
G02X774417Y46378I7874J0D01*
G01X871260D01*
G03X879134Y54252I0J7874D01*
G01Y134331D01*
G02X887008Y142205I7874J0D01*
G01X1011024D01*
G02X1018898Y134331I0J-7874D01*
G01Y54252D01*
G03X1026772Y46378I7874J0D01*
G01X1518118D01*
G02X1525992Y38504I0J-7874D01*
G01Y1969D01*
G03X1527961Y0I1969J0D01*
G01X1794102D01*
G03X1796071Y1969I0J1969D01*
G01Y38504D01*
G02X1803945Y46378I7874J0D01*
G01X1849606D01*
G03X1857480Y54252I0J7874D01*
G01Y305794D01*
G03X1855174Y311361I-7873J0D01*
G01X1846007Y320528D01*
G02X1843701Y326096I5568J5568D01*
G01Y1593983D01*
G03X1841395Y1599550I-7873J0D01*
G01X1834196Y1606749D01*
G02X1831890Y1612317I5568J5568D01*
G01Y1732244D01*
G03X1824016Y1740118I-7874J0D01*
G01X1091791D01*
G03X1089823Y1738150I0J-1968D01*
G01Y1736890D01*
G02X1087854Y1734921I-1969J0D01*
G01X769705D01*
G02X767736Y1736890I0J1969D01*
G01Y1738150D01*
G03X765768Y1740118I-1968J0D01*
G01X33465D01*
G03X25591Y1732244I0J-7874D01*
G01Y1612317D01*
G02X23284Y1606749I-7875J1D01*
G01X10180Y1593645D01*
G01X2306Y311361D02*
G03X0Y305794I5567J-5567D01*
G01Y54252D01*
G03X7874Y46378I7874J0D01*
G01X43709D01*
G02X51583Y38504I0J-7874D01*
G01Y1969D01*
G03X53551Y0I1968J0D01*
G01X319693D01*
G03X321661Y1969I0J1969D01*
G01Y38504D01*
G02X329535Y46378I7874J0D01*
G01X488591D01*
G02X496465Y38504I0J-7874D01*
G01Y22756D01*
G03X498433Y20787I1968J-1D01*
G01X764575D01*
G03X766543Y22756I-1J1969D01*
G01Y38504D01*
G02X774417Y46378I7874J0D01*
G01X871260D01*
G03X879134Y54252I0J7874D01*
G01Y134331D01*
G02X887008Y142205I7874J0D01*
G01X1011024D01*
G02X1018898Y134331I0J-7874D01*
G01Y54252D01*
G03X1026772Y46378I7874J0D01*
G01X1518118D01*
G02X1525992Y38504I0J-7874D01*
G01Y1969D01*
G03X1527961Y0I1969J0D01*
G01X1794102D01*
G03X1796071Y1969I0J1969D01*
G01Y38504D01*
G02X1803945Y46378I7874J0D01*
G01X1849606D01*
G03X1857480Y54252I0J7874D01*
G01Y305794D01*
G03X1855174Y311361I-7873J0D01*
G01X1846007Y320528D01*
G02X1843701Y326096I5568J5568D01*
G01Y1593983D01*
G03X1841395Y1599550I-7873J0D01*
G01X1834196Y1606749D01*
G02X1831890Y1612317I5568J5568D01*
G01Y1732244D01*
G03X1824016Y1740118I-7874J0D01*
G01X1091791D01*
G03X1089823Y1738150I0J-1968D01*
G01Y1736890D01*
G02X1087854Y1734921I-1969J0D01*
G01X769705D01*
G02X767736Y1736890I0J1969D01*
G01Y1738150D01*
G03X765768Y1740118I-1968J0D01*
G01X33465D01*
G03X25591Y1732244I0J-7874D01*
G01Y1612317D01*
G02X23284Y1606749I-7875J1D01*
G01X10180Y1593645D01*
G03X7874Y1588077I5568J-5568D01*
G01X2306Y311361D02*
G03X0Y305794I5567J-5567D01*
G01Y54252D01*
G03X7874Y46378I7874J0D01*
G01X43709D01*
G02X51583Y38504I0J-7874D01*
G01Y1969D01*
G03X53551Y0I1968J0D01*
G01X319693D01*
G03X321661Y1969I0J1969D01*
G01Y38504D01*
G02X329535Y46378I7874J0D01*
G01X488591D01*
G02X496465Y38504I0J-7874D01*
G01Y22756D01*
G03X498433Y20787I1968J-1D01*
G01X764575D01*
G03X766543Y22756I-1J1969D01*
G01Y38504D01*
G02X774417Y46378I7874J0D01*
G01X871260D01*
G03X879134Y54252I0J7874D01*
G01Y134331D01*
G02X887008Y142205I7874J0D01*
G01X1011024D01*
G02X1018898Y134331I0J-7874D01*
G01Y54252D01*
G03X1026772Y46378I7874J0D01*
G01X1518118D01*
G02X1525992Y38504I0J-7874D01*
G01Y1969D01*
G03X1527961Y0I1969J0D01*
G01X1794102D01*
G03X1796071Y1969I0J1969D01*
G01Y38504D01*
G02X1803945Y46378I7874J0D01*
G01X1849606D01*
G03X1857480Y54252I0J7874D01*
G01Y305794D01*
G03X1855174Y311361I-7873J0D01*
G01X1846007Y320528D01*
G02X1843701Y326096I5568J5568D01*
G01Y1593983D01*
G03X1841395Y1599550I-7873J0D01*
G01X1834196Y1606749D01*
G02X1831890Y1612317I5568J5568D01*
G01Y1732244D01*
G03X1824016Y1740118I-7874J0D01*
G01X1091791D01*
G03X1089823Y1738150I0J-1968D01*
G01Y1736890D01*
G02X1087854Y1734921I-1969J0D01*
G01X769705D01*
G02X767736Y1736890I0J1969D01*
G01Y1738150D01*
G03X765768Y1740118I-1968J0D01*
G01X33465D01*
G03X25591Y1732244I0J-7874D01*
G01Y1612317D01*
G02X23284Y1606749I-7875J1D01*
G01X10180Y1593645D01*
G03X7874Y1588077I5568J-5568D01*
G01Y320191D01*
G01X2306Y311361D02*
G03X0Y305794I5567J-5567D01*
G01Y54252D01*
G03X7874Y46378I7874J0D01*
G01X43709D01*
G02X51583Y38504I0J-7874D01*
G01Y1969D01*
G03X53551Y0I1968J0D01*
G01X319693D01*
G03X321661Y1969I0J1969D01*
G01Y38504D01*
G02X329535Y46378I7874J0D01*
G01X488591D01*
G02X496465Y38504I0J-7874D01*
G01Y22756D01*
G03X498433Y20787I1968J-1D01*
G01X764575D01*
G03X766543Y22756I-1J1969D01*
G01Y38504D01*
G02X774417Y46378I7874J0D01*
G01X871260D01*
G03X879134Y54252I0J7874D01*
G01Y134331D01*
G02X887008Y142205I7874J0D01*
G01X1011024D01*
G02X1018898Y134331I0J-7874D01*
G01Y54252D01*
G03X1026772Y46378I7874J0D01*
G01X1518118D01*
G02X1525992Y38504I0J-7874D01*
G01Y1969D01*
G03X1527961Y0I1969J0D01*
G01X1794102D01*
G03X1796071Y1969I0J1969D01*
G01Y38504D01*
G02X1803945Y46378I7874J0D01*
G01X1849606D01*
G03X1857480Y54252I0J7874D01*
G01Y305794D01*
G03X1855174Y311361I-7873J0D01*
G01X1846007Y320528D01*
G02X1843701Y326096I5568J5568D01*
G01Y1593983D01*
G03X1841395Y1599550I-7873J0D01*
G01X1834196Y1606749D01*
G02X1831890Y1612317I5568J5568D01*
G01Y1732244D01*
G03X1824016Y1740118I-7874J0D01*
G01X1091791D01*
G03X1089823Y1738150I0J-1968D01*
G01Y1736890D01*
G02X1087854Y1734921I-1969J0D01*
G01X769705D01*
G02X767736Y1736890I0J1969D01*
G01Y1738150D01*
G03X765768Y1740118I-1968J0D01*
G01X33465D01*
G03X25591Y1732244I0J-7874D01*
G01Y1612317D01*
G02X23284Y1606749I-7875J1D01*
G01X10180Y1593645D01*
G03X7874Y1588077I5568J-5568D01*
G01Y320191D01*
G02X5568Y314623I-7874J0D01*
G01X2306Y311361D02*
G03X0Y305794I5567J-5567D01*
G01Y54252D01*
G03X7874Y46378I7874J0D01*
G01X43709D01*
G02X51583Y38504I0J-7874D01*
G01Y1969D01*
G03X53551Y0I1968J0D01*
G01X319693D01*
G03X321661Y1969I0J1969D01*
G01Y38504D01*
G02X329535Y46378I7874J0D01*
G01X488591D01*
G02X496465Y38504I0J-7874D01*
G01Y22756D01*
G03X498433Y20787I1968J-1D01*
G01X764575D01*
G03X766543Y22756I-1J1969D01*
G01Y38504D01*
G02X774417Y46378I7874J0D01*
G01X871260D01*
G03X879134Y54252I0J7874D01*
G01Y134331D01*
G02X887008Y142205I7874J0D01*
G01X1011024D01*
G02X1018898Y134331I0J-7874D01*
G01Y54252D01*
G03X1026772Y46378I7874J0D01*
G01X1518118D01*
G02X1525992Y38504I0J-7874D01*
G01Y1969D01*
G03X1527961Y0I1969J0D01*
G01X1794102D01*
G03X1796071Y1969I0J1969D01*
G01Y38504D01*
G02X1803945Y46378I7874J0D01*
G01X1849606D01*
G03X1857480Y54252I0J7874D01*
G01Y305794D01*
G03X1855174Y311361I-7873J0D01*
G01X1846007Y320528D01*
G02X1843701Y326096I5568J5568D01*
G01Y1593983D01*
G03X1841395Y1599550I-7873J0D01*
G01X1834196Y1606749D01*
G02X1831890Y1612317I5568J5568D01*
G01Y1732244D01*
G03X1824016Y1740118I-7874J0D01*
G01X1091791D01*
G03X1089823Y1738150I0J-1968D01*
G01Y1736890D01*
G02X1087854Y1734921I-1969J0D01*
G01X769705D01*
G02X767736Y1736890I0J1969D01*
G01Y1738150D01*
G03X765768Y1740118I-1968J0D01*
G01X33465D01*
G03X25591Y1732244I0J-7874D01*
G01Y1612317D01*
G02X23284Y1606749I-7875J1D01*
G01X10180Y1593645D01*
G03X7874Y1588077I5568J-5568D01*
G01Y320191D01*
G02X5568Y314623I-7874J0D01*
G01X2306Y311361D01*
G01D02*
G03X0Y305793I5568J-5568D01*
G01X2306Y311361D02*
G03X0Y305793I5568J-5568D01*
G01X1525992Y8492D02*
Y1969D01*
G03X1527961Y0I1969J0D01*
G01X1794102D01*
G03X1796071Y1969I0J1969D01*
G01Y38504D01*
G02X1803945Y46378I7874J0D01*
G01X1849606D01*
G03X1857480Y54252I0J7874D01*
G01Y305793D01*
G03X1855174Y311361I-7874J0D01*
G01X1846007Y320528D01*
G02X1843701Y326096I5568J5568D01*
G01Y1593982D01*
G03X1841395Y1599550I-7874J0D01*
G01X1834196Y1606749D01*
G02X1831890Y1612316I5567J5567D01*
G01Y1732244D01*
G03X1824016Y1740118I-7874J0D01*
G01X1091791D01*
G03X1089823Y1738149I0J-1968D01*
G01Y1736890D01*
G02X1087854Y1734921I-1969J0D01*
G01X769705D01*
G02X767736Y1736890I0J1969D01*
G01Y1738149D01*
G03X765768Y1740118I-1968J0D01*
G01X33465D01*
G03X25591Y1732244I0J-7874D01*
G01Y1612316D01*
G02X23284Y1606749I-7873J1D01*
G01X10180Y1593645D01*
G03X7874Y1588077I5568J-5568D01*
G01Y320190D01*
G02X5568Y314623I-7873J0D01*
G01X2306Y311361D01*
G01X1796071Y16549D02*
Y38504D01*
G02X1803945Y46378I7874J0D01*
G01X1849606D01*
G03X1857480Y54252I0J7874D01*
G01Y305793D01*
G03X1855174Y311361I-7874J0D01*
G01X1846007Y320528D01*
G02X1843701Y326096I5568J5568D01*
G01Y1593982D01*
G03X1841395Y1599550I-7874J0D01*
G01X1834196Y1606749D01*
G02X1831890Y1612316I5567J5567D01*
G01Y1732244D01*
G03X1824016Y1740118I-7874J0D01*
G01X1091791D01*
G03X1089823Y1738149I0J-1968D01*
G01Y1736890D01*
G02X1087854Y1734921I-1969J0D01*
G01X769705D01*
G02X767736Y1736890I0J1969D01*
G01Y1738149D01*
G03X765768Y1740118I-1968J0D01*
G01X33465D01*
G03X25591Y1732244I0J-7874D01*
G01Y1612316D01*
G02X23284Y1606749I-7873J1D01*
G01X10180Y1593645D01*
G03X7874Y1588077I5568J-5568D01*
G01Y320190D01*
G02X5568Y314623I-7873J0D01*
G01X2306Y311361D01*
G01D02*
G03X0Y305794I5567J-5567D01*
G01X1796071Y16549D02*
Y38504D01*
G02X1803945Y46378I7874J0D01*
G01X1849606D01*
G03X1857480Y54252I0J7874D01*
G01Y305793D01*
G03X1855174Y311361I-7874J0D01*
G01X1846007Y320528D01*
G02X1843701Y326096I5568J5568D01*
G01Y1593982D01*
G03X1841395Y1599550I-7874J0D01*
G01X1834196Y1606749D01*
G02X1831890Y1612316I5567J5567D01*
G01Y1732244D01*
G03X1824016Y1740118I-7874J0D01*
G01X1091791D01*
G03X1089823Y1738149I0J-1968D01*
G01Y1736890D01*
G02X1087854Y1734921I-1969J0D01*
G01X769705D01*
G02X767736Y1736890I0J1969D01*
G01Y1738149D01*
G03X765768Y1740118I-1968J0D01*
G01X33465D01*
G03X25591Y1732244I0J-7874D01*
G01Y1612316D01*
G02X23284Y1606749I-7873J1D01*
G01X10180Y1593645D01*
G03X7874Y1588077I5568J-5568D01*
G01Y320190D01*
G02X5568Y314623I-7873J0D01*
G01X1796071Y16549D02*
Y38504D01*
G02X1803945Y46378I7874J0D01*
G01X1849606D01*
G03X1857480Y54252I0J7874D01*
G01Y305793D01*
G03X1855174Y311361I-7874J0D01*
G01X1846007Y320528D01*
G02X1843701Y326096I5568J5568D01*
G01Y1593982D01*
G03X1841395Y1599550I-7874J0D01*
G01X1834196Y1606749D01*
G02X1831890Y1612316I5567J5567D01*
G01Y1732244D01*
G03X1824016Y1740118I-7874J0D01*
G01X1091791D01*
G03X1089823Y1738149I0J-1968D01*
G01Y1736890D01*
G02X1087854Y1734921I-1969J0D01*
G01X769705D01*
G02X767736Y1736890I0J1969D01*
G01Y1738149D01*
G03X765768Y1740118I-1968J0D01*
G01X33465D01*
G03X25591Y1732244I0J-7874D01*
G01Y1612316D01*
G02X23284Y1606749I-7873J1D01*
G01X10180Y1593645D01*
G03X7874Y1588077I5568J-5568D01*
G01Y320190D01*
G02X5568Y314623I-7873J0D01*
G01X118813Y1747992D02*
X7874D01*
G02X0Y1755866I0J7874D01*
G01Y1815072D01*
G02X7874Y1822946I7874J0D01*
G01X1849606D01*
G02X1857480Y1815072I0J-7874D01*
G01Y1755866D01*
G02X1849606Y1747992I-7874J0D01*
G01X1709976D01*
G01X51000Y1822946D02*
X7874D01*
G03X0Y1815072I0J-7874D01*
G01Y1799324D01*
G01Y1832789D02*
Y1918261D01*
G01Y1832946D02*
Y1872946D01*
G01X993062Y1862946D02*
X0D01*
G01X7000Y1864446D02*
X0Y1862946D01*
X7000Y1861446D01*
Y1864446D01*
G01X11920Y46378D02*
G02Y38504I0J-3937D01*
G01X1796071Y16549D02*
Y38504D01*
G02X1803945Y46378I7874J0D01*
G01X1849606D01*
G03X1857480Y54252I0J7874D01*
G01Y305793D01*
G03X1855174Y311361I-7874J0D01*
G01X1846007Y320528D01*
G02X1843701Y326096I5568J5568D01*
G01Y1593982D01*
G03X1841395Y1599550I-7874J0D01*
G01X1834196Y1606749D01*
G02X1831890Y1612316I5567J5567D01*
G01Y1732244D01*
G03X1824016Y1740118I-7874J0D01*
G01X1091791D01*
G03X1089823Y1738149I0J-1968D01*
G01Y1736890D01*
G02X1087854Y1734921I-1969J0D01*
G01X769705D01*
G02X767736Y1736890I0J1969D01*
G01Y1738149D01*
G03X765768Y1740118I-1968J0D01*
G01X33465D01*
G03X25591Y1732244I0J-7874D01*
G01Y1612316D01*
G02X23284Y1606749I-7873J1D01*
G01X10180Y1593645D01*
G03X7874Y1588077I5568J-5568D01*
G01Y320190D01*
G01X1796071Y16549D02*
Y38504D01*
G02X1803945Y46378I7874J0D01*
G01X1849606D01*
G03X1857480Y54252I0J7874D01*
G01Y305793D01*
G03X1855174Y311361I-7874J0D01*
G01X1846007Y320528D01*
G02X1843701Y326096I5568J5568D01*
G01Y1593982D01*
G03X1841395Y1599550I-7874J0D01*
G01X1834196Y1606749D01*
G02X1831890Y1612316I5567J5567D01*
G01Y1732244D01*
G03X1824016Y1740118I-7874J0D01*
G01X1091791D01*
G03X1089823Y1738149I0J-1968D01*
G01Y1736890D01*
G02X1087854Y1734921I-1969J0D01*
G01X769705D01*
G02X767736Y1736890I0J1969D01*
G01Y1738149D01*
G03X765768Y1740118I-1968J0D01*
G01X33465D01*
G03X25591Y1732244I0J-7874D01*
G01Y1612316D01*
G02X23284Y1606749I-7873J1D01*
G01X10180Y1593645D01*
G03X7874Y1588077I5568J-5568D01*
G01Y320190D01*
G01X1796071Y16549D02*
Y38504D01*
G02X1803945Y46378I7874J0D01*
G01X1849606D01*
G03X1857480Y54252I0J7874D01*
G01Y305793D01*
G03X1855174Y311361I-7874J0D01*
G01X1846007Y320528D01*
G02X1843701Y326096I5568J5568D01*
G01Y1593982D01*
G03X1841395Y1599550I-7874J0D01*
G01X1834196Y1606749D01*
G02X1831890Y1612316I5567J5567D01*
G01Y1732244D01*
G03X1824016Y1740118I-7874J0D01*
G01X1091791D01*
G03X1089823Y1738149I0J-1968D01*
G01Y1736890D01*
G02X1087854Y1734921I-1969J0D01*
G01X769705D01*
G02X767736Y1736890I0J1969D01*
G01Y1738149D01*
G03X765768Y1740118I-1968J0D01*
G01X33465D01*
G03X25591Y1732244I0J-7874D01*
G01Y1612316D01*
G02X23284Y1606749I-7873J1D01*
G01X10180Y1593645D01*
G01X1796071Y16549D02*
Y38504D01*
G02X1803945Y46378I7874J0D01*
G01X1849606D01*
G03X1857480Y54252I0J7874D01*
G01Y305793D01*
G03X1855174Y311361I-7874J0D01*
G01X1846007Y320528D01*
G02X1843701Y326096I5568J5568D01*
G01Y1593982D01*
G03X1841395Y1599550I-7874J0D01*
G01X1834196Y1606749D01*
G02X1831890Y1612316I5567J5567D01*
G01Y1732244D01*
G03X1824016Y1740118I-7874J0D01*
G01X1091791D01*
G03X1089823Y1738149I0J-1968D01*
G01Y1736890D01*
G02X1087854Y1734921I-1969J0D01*
G01X769705D01*
G02X767736Y1736890I0J1969D01*
G01Y1738149D01*
G03X765768Y1740118I-1968J0D01*
G01X33465D01*
G03X25591Y1732244I0J-7874D01*
G01Y1612316D01*
G02X23284Y1606749I-7873J1D01*
G01X10180Y1593645D01*
G03X7874Y1588077I5568J-5568D01*
G01X1796071Y16549D02*
Y38504D01*
G02X1803945Y46378I7874J0D01*
G01X1849606D01*
G03X1857480Y54252I0J7874D01*
G01Y305793D01*
G03X1855174Y311361I-7874J0D01*
G01X1846007Y320528D01*
G02X1843701Y326096I5568J5568D01*
G01Y1593982D01*
G03X1841395Y1599550I-7874J0D01*
G01X1834196Y1606749D01*
G02X1831890Y1612316I5567J5567D01*
G01Y1732244D01*
G03X1824016Y1740118I-7874J0D01*
G01X1091791D01*
G03X1089823Y1738149I0J-1968D01*
G01Y1736890D01*
G02X1087854Y1734921I-1969J0D01*
G01X769705D01*
G02X767736Y1736890I0J1969D01*
G01Y1738149D01*
G03X765768Y1740118I-1968J0D01*
G01X33465D01*
G03X25591Y1732244I0J-7874D01*
G01Y1612316D01*
G02X23284Y1606749I-7873J1D01*
G01X10180Y1593645D01*
G01X1796071Y16549D02*
Y38504D01*
G02X1803945Y46378I7874J0D01*
G01X1849606D01*
G03X1857480Y54252I0J7874D01*
G01Y305793D01*
G03X1855174Y311361I-7874J0D01*
G01X1846007Y320528D01*
G02X1843701Y326096I5568J5568D01*
G01Y1593982D01*
G03X1841395Y1599550I-7874J0D01*
G01X1834196Y1606749D01*
G02X1831890Y1612316I5567J5567D01*
G01Y1732244D01*
G03X1824016Y1740118I-7874J0D01*
G01X1091791D01*
G03X1089823Y1738149I0J-1968D01*
G01Y1736890D01*
G02X1087854Y1734921I-1969J0D01*
G01X769705D01*
G02X767736Y1736890I0J1969D01*
G01Y1738149D01*
G03X765768Y1740118I-1968J0D01*
G01X33465D01*
G03X25591Y1732244I0J-7874D01*
G01Y1612316D01*
G02X23284Y1606749I-7873J1D01*
G01X10180Y1593645D01*
G03X7874Y1588077I5568J-5568D01*
G01X31606Y46378D02*
G03Y38504I0J-3937D01*
G01X1796071Y16549D02*
Y38504D01*
G02X1803945Y46378I7874J0D01*
G01X1849606D01*
G03X1857480Y54252I0J7874D01*
G01Y305793D01*
G03X1855174Y311361I-7874J0D01*
G01X1846007Y320528D01*
G02X1843701Y326096I5568J5568D01*
G01Y1593982D01*
G03X1841395Y1599550I-7874J0D01*
G01X1834196Y1606749D01*
G02X1831890Y1612316I5567J5567D01*
G01Y1732244D01*
G03X1824016Y1740118I-7874J0D01*
G01X1091791D01*
G03X1089823Y1738149I0J-1968D01*
G01Y1736890D01*
G02X1087854Y1734921I-1969J0D01*
G01X769705D01*
G02X767736Y1736890I0J1969D01*
G01Y1738149D01*
G03X765768Y1740118I-1968J0D01*
G01X33465D01*
G03X25591Y1732244I0J-7874D01*
G01Y1612316D01*
G02X23284Y1606749I-7873J1D01*
G01X1796071Y16549D02*
Y38504D01*
G02X1803945Y46378I7874J0D01*
G01X1849606D01*
G03X1857480Y54252I0J7874D01*
G01Y305793D01*
G03X1855174Y311361I-7874J0D01*
G01X1846007Y320528D01*
G02X1843701Y326096I5568J5568D01*
G01Y1593982D01*
G03X1841395Y1599550I-7874J0D01*
G01X1834196Y1606749D01*
G02X1831890Y1612316I5567J5567D01*
G01Y1732244D01*
G03X1824016Y1740118I-7874J0D01*
G01X1091791D01*
G03X1089823Y1738149I0J-1968D01*
G01Y1736890D01*
G02X1087854Y1734921I-1969J0D01*
G01X769705D01*
G02X767736Y1736890I0J1969D01*
G01Y1738149D01*
G03X765768Y1740118I-1968J0D01*
G01X33465D01*
G03X25591Y1732244I0J-7874D01*
G01Y1612316D01*
G02X23284Y1606749I-7873J1D01*
G01X1796071Y16549D02*
Y38504D01*
G02X1803945Y46378I7874J0D01*
G01X1849606D01*
G03X1857480Y54252I0J7874D01*
G01Y305793D01*
G03X1855174Y311361I-7874J0D01*
G01X1846007Y320528D01*
G02X1843701Y326096I5568J5568D01*
G01Y1593982D01*
G03X1841395Y1599550I-7874J0D01*
G01X1834196Y1606749D01*
G02X1831890Y1612316I5567J5567D01*
G01Y1732244D01*
G03X1824016Y1740118I-7874J0D01*
G01X1091791D01*
G03X1089823Y1738149I0J-1968D01*
G01Y1736890D01*
G02X1087854Y1734921I-1969J0D01*
G01X769705D01*
G02X767736Y1736890I0J1969D01*
G01Y1738149D01*
G03X765768Y1740118I-1968J0D01*
G01X33465D01*
G03X25591Y1732244I0J-7874D01*
G01Y1612316D01*
G01X1796071Y16549D02*
Y38504D01*
G02X1803945Y46378I7874J0D01*
G01X1849606D01*
G03X1857480Y54252I0J7874D01*
G01Y305793D01*
G03X1855174Y311361I-7874J0D01*
G01X1846007Y320528D01*
G02X1843701Y326096I5568J5568D01*
G01Y1593982D01*
G03X1841395Y1599550I-7874J0D01*
G01X1834196Y1606749D01*
G02X1831890Y1612316I5567J5567D01*
G01Y1732244D01*
G03X1824016Y1740118I-7874J0D01*
G01X1091791D01*
G03X1089823Y1738149I0J-1968D01*
G01Y1736890D01*
G02X1087854Y1734921I-1969J0D01*
G01X769705D01*
G02X767736Y1736890I0J1969D01*
G01Y1738149D01*
G03X765768Y1740118I-1968J0D01*
G01X33465D01*
G03X25591Y1732244I0J-7874D01*
G01Y1612316D01*
G01X1796071Y16549D02*
Y38504D01*
G02X1803945Y46378I7874J0D01*
G01X1849606D01*
G03X1857480Y54252I0J7874D01*
G01Y305793D01*
G03X1855174Y311361I-7874J0D01*
G01X1846007Y320528D01*
G02X1843701Y326096I5568J5568D01*
G01Y1593982D01*
G03X1841395Y1599550I-7874J0D01*
G01X1834196Y1606749D01*
G02X1831890Y1612316I5567J5567D01*
G01Y1732244D01*
G03X1824016Y1740118I-7874J0D01*
G01X1091791D01*
G03X1089823Y1738149I0J-1968D01*
G01Y1736890D01*
G02X1087854Y1734921I-1969J0D01*
G01X769705D01*
G02X767736Y1736890I0J1969D01*
G01Y1738149D01*
G03X765768Y1740118I-1968J0D01*
G01X33465D01*
G01X1796071Y16549D02*
Y38504D01*
G02X1803945Y46378I7874J0D01*
G01X1849606D01*
G03X1857480Y54252I0J7874D01*
G01Y305793D01*
G03X1855174Y311361I-7874J0D01*
G01X1846007Y320528D01*
G02X1843701Y326096I5568J5568D01*
G01Y1593982D01*
G03X1841395Y1599550I-7874J0D01*
G01X1834196Y1606749D01*
G02X1831890Y1612316I5567J5567D01*
G01Y1732244D01*
G03X1824016Y1740118I-7874J0D01*
G01X1091791D01*
G03X1089823Y1738149I0J-1968D01*
G01Y1736890D01*
G02X1087854Y1734921I-1969J0D01*
G01X769705D01*
G02X767736Y1736890I0J1969D01*
G01Y1738149D01*
G03X765768Y1740118I-1968J0D01*
G01X33465D01*
G03X25591Y1732244I0J-7874D01*
G01X1796071Y16549D02*
Y38504D01*
G02X1803945Y46378I7874J0D01*
G01X1849606D01*
G03X1857480Y54252I0J7874D01*
G01Y305793D01*
G03X1855174Y311361I-7874J0D01*
G01X1846007Y320528D01*
G02X1843701Y326096I5568J5568D01*
G01Y1593982D01*
G03X1841395Y1599550I-7874J0D01*
G01X1834196Y1606749D01*
G02X1831890Y1612316I5567J5567D01*
G01Y1732244D01*
G03X1824016Y1740118I-7874J0D01*
G01X1091791D01*
G03X1089823Y1738149I0J-1968D01*
G01Y1736890D01*
G02X1087854Y1734921I-1969J0D01*
G01X769705D01*
G02X767736Y1736890I0J1969D01*
G01Y1738149D01*
G03X765768Y1740118I-1968J0D01*
G01X33465D01*
G01X1796071Y16549D02*
Y38504D01*
G02X1803945Y46378I7874J0D01*
G01X1849606D01*
G03X1857480Y54252I0J7874D01*
G01Y305793D01*
G03X1855174Y311361I-7874J0D01*
G01X1846007Y320528D01*
G02X1843701Y326096I5568J5568D01*
G01Y1593982D01*
G03X1841395Y1599550I-7874J0D01*
G01X1834196Y1606749D01*
G02X1831890Y1612316I5567J5567D01*
G01Y1732244D01*
G03X1824016Y1740118I-7874J0D01*
G01X1091791D01*
G03X1089823Y1738149I0J-1968D01*
G01Y1736890D01*
G02X1087854Y1734921I-1969J0D01*
G01X769705D01*
G02X767736Y1736890I0J1969D01*
G01Y1738149D01*
G03X765768Y1740118I-1968J0D01*
G01X33465D01*
G03X25591Y1732244I0J-7874D01*
G01X51583Y10560D02*
Y1969D01*
G03X53551Y0I1968J0D01*
G01X51583Y10560D02*
Y1969D01*
G03X53551Y0I1968J0D01*
G01X319693D01*
G01X51583Y10560D02*
Y1969D01*
G03X53551Y0I1968J0D01*
G01X319693D01*
G03X321661Y1969I0J1969D01*
G01X51583Y10560D02*
Y1969D01*
G03X53551Y0I1968J0D01*
G01X319693D01*
G03X321661Y1969I0J1969D01*
G01Y38504D01*
G02X329535Y46378I7874J0D01*
G01X488591D01*
G02X496465Y38504I0J-7874D01*
G01Y22756D01*
G01X51583Y10560D02*
Y1969D01*
G03X53551Y0I1968J0D01*
G01X319693D01*
G03X321661Y1969I0J1969D01*
G01Y10560D01*
G01X51583D02*
Y1969D01*
G03X53551Y0I1968J0D01*
G01X319693D01*
G03X321661Y1969I0J1969D01*
G01Y10560D01*
G01X51583D02*
Y1969D01*
G03X53551Y0I1968J0D01*
G01X319693D01*
G03X321661Y1969I0J1969D01*
G01Y10560D01*
G01X51583D02*
Y1969D01*
G03X53551Y0I1968J0D01*
G01X319693D01*
G03X321661Y1969I0J1969D01*
G01Y10560D01*
G01X51583D02*
Y1969D01*
G03X53551Y0I1968J0D01*
G01X319693D01*
G03X321661Y1969I0J1969D01*
G01Y10560D01*
G01X51583D02*
Y1969D01*
G03X53551Y0I1968J0D01*
G01X319693D01*
G03X321661Y1969I0J1969D01*
G01Y10560D01*
G01X51583D02*
Y1969D01*
G03X53551Y0I1968J0D01*
G01X319693D01*
G03X321661Y1969I0J1969D01*
G01Y10560D01*
G01X51583D02*
Y1969D01*
G03X53551Y0I1968J0D01*
G01X319693D01*
G03X321661Y1969I0J1969D01*
G01Y10560D01*
G01X51583D02*
Y1969D01*
G03X53551Y0I1968J0D01*
G01X319693D01*
G03X321661Y1969I0J1969D01*
G01Y10560D01*
G01X51583D02*
Y1969D01*
G03X53551Y0I1968J0D01*
G01X319693D01*
G03X321661Y1969I0J1969D01*
G01Y10560D01*
G01X51583D02*
Y1969D01*
G03X53551Y0I1968J0D01*
G01X319693D01*
G03X321661Y1969I0J1969D01*
G01Y10560D01*
G01X51583D02*
Y1969D01*
G03X53551Y0I1968J0D01*
G01X319693D01*
G03X321661Y1969I0J1969D01*
G01Y10560D01*
G01X51583D02*
Y1969D01*
G03X53551Y0I1968J0D01*
G01X319693D01*
G03X321661Y1969I0J1969D01*
G01Y10560D01*
G01X51583D02*
Y1969D01*
G03X53551Y0I1968J0D01*
G01X319693D01*
G03X321661Y1969I0J1969D01*
G01Y10560D01*
G01X51583D02*
Y1969D01*
G03X53551Y0I1968J0D01*
G01X319693D01*
G03X321661Y1969I0J1969D01*
G01Y10560D01*
G01X51583D02*
Y1969D01*
G03X53551Y0I1968J0D01*
G01X319693D01*
G03X321661Y1969I0J1969D01*
G01Y10560D01*
G01X51583D02*
Y1969D01*
G03X53551Y0I1968J0D01*
G01X319693D01*
G03X321661Y1969I0J1969D01*
G01Y10560D01*
G01X51583D02*
Y1969D01*
G03X53551Y0I1968J0D01*
G01X319693D01*
G03X321661Y1969I0J1969D01*
G01Y10560D01*
G01X51583D02*
Y1969D01*
G03X53551Y0I1968J0D01*
G01X319693D01*
G03X321661Y1969I0J1969D01*
G01Y10560D01*
G01X51583D02*
Y1969D01*
G03X53551Y0I1968J0D01*
G01X319693D01*
G03X321661Y1969I0J1969D01*
G01Y10560D01*
G01X51583D02*
Y1969D01*
G03X53551Y0I1968J0D01*
G01X319693D01*
G03X321661Y1969I0J1969D01*
G01Y10560D01*
G01X51583D02*
Y1969D01*
G03X53551Y0I1968J0D01*
G01X319693D01*
G03X321661Y1969I0J1969D01*
G01Y10560D01*
G01X51583D02*
Y1969D01*
G03X53551Y0I1968J0D01*
G01X319693D01*
G03X321661Y1969I0J1969D01*
G01Y10560D01*
G01X51583D02*
Y1969D01*
G03X53551Y0I1968J0D01*
G01X319693D01*
G03X321661Y1969I0J1969D01*
G01Y10560D01*
G01X51583D02*
Y1969D01*
G03X53551Y0I1968J0D01*
G01X319693D01*
G03X321661Y1969I0J1969D01*
G01Y10560D01*
G01X51583D02*
Y1969D01*
G03X53551Y0I1968J0D01*
G01X319693D01*
G03X321661Y1969I0J1969D01*
G01Y10560D01*
G01X51583D02*
Y1969D01*
G03X53551Y0I1968J0D01*
G01X319693D01*
G03X321661Y1969I0J1969D01*
G01Y10560D01*
G01X51583D02*
Y1969D01*
G03X53551Y0I1968J0D01*
G01X319693D01*
G03X321661Y1969I0J1969D01*
G01Y10560D01*
G01X51583D02*
Y1969D01*
G03X53551Y0I1968J0D01*
G01X319693D01*
G03X321661Y1969I0J1969D01*
G01Y10560D01*
G01X51583D02*
Y1969D01*
G03X53551Y0I1968J0D01*
G01X319693D01*
G03X321661Y1969I0J1969D01*
G01Y10560D01*
G01X51583D02*
Y1969D01*
G03X53551Y0I1968J0D01*
G01X319693D01*
G03X321661Y1969I0J1969D01*
G01Y10560D01*
G01X51583D02*
Y1969D01*
G03X53551Y0I1968J0D01*
G01X319693D01*
G03X321661Y1969I0J1969D01*
G01Y10560D01*
G01X51583D02*
Y1969D01*
G03X53551Y0I1968J0D01*
G01X319693D01*
G03X321661Y1969I0J1969D01*
G01Y10560D01*
G01X51583D02*
Y1969D01*
G03X53551Y0I1968J0D01*
G01X319693D01*
G03X321661Y1969I0J1969D01*
G01Y10560D01*
G01X51583D02*
Y1969D01*
G03X53551Y0I1968J0D01*
G01X319693D01*
G03X321661Y1969I0J1969D01*
G01Y10560D01*
G01X51583D02*
Y1969D01*
G03X53551Y0I1968J0D01*
G01X319693D01*
G03X321661Y1969I0J1969D01*
G01Y10560D01*
G01X51583D02*
Y1969D01*
G03X53551Y0I1968J0D01*
G01X319693D01*
G03X321661Y1969I0J1969D01*
G01Y10560D01*
G01X51583D02*
Y1969D01*
G03X53551Y0I1968J0D01*
G01X319693D01*
G03X321661Y1969I0J1969D01*
G01Y10560D01*
G01X51583D02*
Y1969D01*
G03X53551Y0I1968J0D01*
G01X319693D01*
G03X321661Y1969I0J1969D01*
G01Y10560D01*
G01X51583D02*
Y1969D01*
G03X53551Y0I1968J0D01*
G01X319693D01*
G03X321661Y1969I0J1969D01*
G01Y10560D01*
G01X51583D02*
Y1969D01*
G03X53551Y0I1968J0D01*
G01X319693D01*
G03X321661Y1969I0J1969D01*
G01Y10560D01*
G01X51583D02*
Y1969D01*
G03X53551Y0I1968J0D01*
G01X319693D01*
G03X321661Y1969I0J1969D01*
G01Y10560D01*
G01X51583D02*
Y1969D01*
G03X53551Y0I1968J0D01*
G01X319693D01*
G03X321661Y1969I0J1969D01*
G01Y10560D01*
G01X51583D02*
Y1969D01*
G03X53551Y0I1968J0D01*
G01X319693D01*
G03X321661Y1969I0J1969D01*
G01Y10560D01*
G01X51583D02*
Y1969D01*
G03X53551Y0I1968J0D01*
G01X319693D01*
G03X321661Y1969I0J1969D01*
G01Y10560D01*
G01X51583D02*
Y1969D01*
G03X53551Y0I1968J0D01*
G01X319693D01*
G03X321661Y1969I0J1969D01*
G01Y10560D01*
G01X51583D02*
Y1969D01*
G03X53551Y0I1968J0D01*
G01X319693D01*
G03X321661Y1969I0J1969D01*
G01Y10560D01*
G01X51583D02*
Y1969D01*
G03X53551Y0I1968J0D01*
G01X319693D01*
G03X321661Y1969I0J1969D01*
G01Y10560D01*
G01X51583D02*
Y1969D01*
G03X53551Y0I1968J0D01*
G01X319693D01*
G03X321661Y1969I0J1969D01*
G01Y10560D01*
G01X51583D02*
Y1969D01*
G03X53551Y0I1968J0D01*
G01X319693D01*
G03X321661Y1969I0J1969D01*
G01Y10560D01*
G01X51583D02*
Y1969D01*
G03X53551Y0I1968J0D01*
G01X319693D01*
G03X321661Y1969I0J1969D01*
G01Y10560D01*
G01X51583D02*
Y1969D01*
G03X53551Y0I1968J0D01*
G01X319693D01*
G03X321661Y1969I0J1969D01*
G01Y10560D01*
G01X51583D02*
Y1969D01*
G03X53551Y0I1968J0D01*
G01X319693D01*
G03X321661Y1969I0J1969D01*
G01Y10560D01*
G01X51583D02*
Y1969D01*
G03X53551Y0I1968J0D01*
G01X319693D01*
G03X321661Y1969I0J1969D01*
G01Y10560D01*
G01X51583D02*
Y1969D01*
G01Y10560D02*
Y1969D01*
G03X53551Y0I1968J0D01*
G01X51583Y10560D02*
Y1969D01*
G03X53551Y0I1968J0D01*
G01X319693D01*
G01X51583Y10560D02*
Y1969D01*
G03X53551Y0I1968J0D01*
G01X319693D01*
G03X321661Y1969I0J1969D01*
G01X51583Y10560D02*
Y1969D01*
G03X53551Y0I1968J0D01*
G01X319693D01*
G03X321661Y1969I0J1969D01*
G01Y10560D01*
G01X51583D02*
Y1969D01*
G03X53551Y0I1968J0D01*
G01X319693D01*
G03X321661Y1969I0J1969D01*
G01Y10560D01*
G01X51583D02*
Y1969D01*
G03X53551Y0I1968J0D01*
G01X319693D01*
G03X321661Y1969I0J1969D01*
G01Y10560D01*
G01X51583D02*
Y1969D01*
G03X53551Y0I1968J0D01*
G01X319693D01*
G03X321661Y1969I0J1969D01*
G01Y10560D01*
G01X51583D02*
Y1969D01*
G03X53551Y0I1968J0D01*
G01X319693D01*
G03X321661Y1969I0J1969D01*
G01Y10560D01*
G01X51583D02*
Y1969D01*
G03X53551Y0I1968J0D01*
G01X319693D01*
G03X321661Y1969I0J1969D01*
G01Y10560D01*
G01X51583D02*
Y1969D01*
G03X53551Y0I1968J0D01*
G01X319693D01*
G03X321661Y1969I0J1969D01*
G01Y10560D01*
G01X51583D02*
Y1969D01*
G03X53551Y0I1968J0D01*
G01X319693D01*
G03X321661Y1969I0J1969D01*
G01Y10560D01*
G01X51583D02*
Y1969D01*
G03X53551Y0I1968J0D01*
G01X319693D01*
G03X321661Y1969I0J1969D01*
G01Y10560D01*
G01X51583D02*
Y1969D01*
G03X53551Y0I1968J0D01*
G01X319693D01*
G03X321661Y1969I0J1969D01*
G01Y10560D01*
G01X51583D02*
Y1969D01*
G03X53551Y0I1968J0D01*
G01X319693D01*
G03X321661Y1969I0J1969D01*
G01Y10560D01*
G01X51583D02*
Y1969D01*
G03X53551Y0I1968J0D01*
G01X319693D01*
G03X321661Y1969I0J1969D01*
G01Y10560D01*
G01X51583D02*
Y1969D01*
G03X53551Y0I1968J0D01*
G01X319693D01*
G03X321661Y1969I0J1969D01*
G01Y10560D01*
G01X51583D02*
Y1969D01*
G03X53551Y0I1968J0D01*
G01X319693D01*
G03X321661Y1969I0J1969D01*
G01Y10560D01*
G01X51583D02*
Y1969D01*
G03X53551Y0I1968J0D01*
G01X319693D01*
G03X321661Y1969I0J1969D01*
G01Y10560D01*
G01X51583D02*
Y1969D01*
G03X53551Y0I1968J0D01*
G01X319693D01*
G03X321661Y1969I0J1969D01*
G01Y10560D01*
G01X51583D02*
Y1969D01*
G03X53551Y0I1968J0D01*
G01X319693D01*
G03X321661Y1969I0J1969D01*
G01Y10560D01*
G01X51583D02*
Y1969D01*
G03X53551Y0I1968J0D01*
G01X319693D01*
G03X321661Y1969I0J1969D01*
G01Y10560D01*
G01X51583D02*
Y1969D01*
G03X53551Y0I1968J0D01*
G01X319693D01*
G03X321661Y1969I0J1969D01*
G01Y10560D01*
G01X51583D02*
Y1969D01*
G03X53551Y0I1968J0D01*
G01X319693D01*
G03X321661Y1969I0J1969D01*
G01Y10560D01*
G01X51583D02*
Y1969D01*
G03X53551Y0I1968J0D01*
G01X319693D01*
G03X321661Y1969I0J1969D01*
G01Y10560D01*
G01X51583D02*
Y1969D01*
G03X53551Y0I1968J0D01*
G01X319693D01*
G03X321661Y1969I0J1969D01*
G01Y10560D01*
G01X51583D02*
Y1969D01*
G03X53551Y0I1968J0D01*
G01X319693D01*
G03X321661Y1969I0J1969D01*
G01Y10560D01*
G01X51583D02*
Y1969D01*
G03X53551Y0I1968J0D01*
G01X319693D01*
G03X321661Y1969I0J1969D01*
G01Y10560D01*
G01X51583D02*
Y1969D01*
G03X53551Y0I1968J0D01*
G01X319693D01*
G03X321661Y1969I0J1969D01*
G01Y10560D01*
G01X51583D02*
Y1969D01*
G03X53551Y0I1968J0D01*
G01X319693D01*
G03X321661Y1969I0J1969D01*
G01Y10560D01*
G01X51583D02*
Y1969D01*
G03X53551Y0I1968J0D01*
G01X319693D01*
G03X321661Y1969I0J1969D01*
G01Y10560D01*
G01X51583D02*
Y1969D01*
G03X53551Y0I1968J0D01*
G01X319693D01*
G03X321661Y1969I0J1969D01*
G01Y10560D01*
G01X51583D02*
Y1969D01*
G03X53551Y0I1968J0D01*
G01X319693D01*
G03X321661Y1969I0J1969D01*
G01Y10560D01*
G01X51583D02*
Y1969D01*
G03X53551Y0I1968J0D01*
G01X319693D01*
G03X321661Y1969I0J1969D01*
G01Y10560D01*
G01X51583D02*
Y1969D01*
G03X53551Y0I1968J0D01*
G01X319693D01*
G03X321661Y1969I0J1969D01*
G01Y10560D01*
G01X51583D02*
Y1969D01*
G03X53551Y0I1968J0D01*
G01X319693D01*
G03X321661Y1969I0J1969D01*
G01Y10560D01*
G01X51583D02*
Y1969D01*
G03X53551Y0I1968J0D01*
G01X319693D01*
G03X321661Y1969I0J1969D01*
G01Y10560D01*
G01X51583D02*
Y1969D01*
G03X53551Y0I1968J0D01*
G01X319693D01*
G03X321661Y1969I0J1969D01*
G01Y10560D01*
G01X51583D02*
Y1969D01*
G03X53551Y0I1968J0D01*
G01X319693D01*
G03X321661Y1969I0J1969D01*
G01Y10560D01*
G01X51583D02*
Y1969D01*
G03X53551Y0I1968J0D01*
G01X319693D01*
G03X321661Y1969I0J1969D01*
G01Y10560D01*
G01X51583D02*
Y1969D01*
G03X53551Y0I1968J0D01*
G01X319693D01*
G03X321661Y1969I0J1969D01*
G01Y10560D01*
G01X51583D02*
Y1969D01*
G03X53551Y0I1968J0D01*
G01X319693D01*
G03X321661Y1969I0J1969D01*
G01Y10560D01*
G01X51583D02*
Y1969D01*
G03X53551Y0I1968J0D01*
G01X319693D01*
G03X321661Y1969I0J1969D01*
G01Y10560D01*
G01X51583D02*
Y1969D01*
G03X53551Y0I1968J0D01*
G01X319693D01*
G03X321661Y1969I0J1969D01*
G01Y10560D01*
G01X51583D02*
Y1969D01*
G03X53551Y0I1968J0D01*
G01X319693D01*
G03X321661Y1969I0J1969D01*
G01Y10560D01*
G01X51583D02*
Y1969D01*
G03X53551Y0I1968J0D01*
G01X319693D01*
G03X321661Y1969I0J1969D01*
G01Y10560D01*
G01X51583D02*
Y1969D01*
G03X53551Y0I1968J0D01*
G01X319693D01*
G03X321661Y1969I0J1969D01*
G01Y10560D01*
G01X51583D02*
Y1969D01*
G03X53551Y0I1968J0D01*
G01X319693D01*
G03X321661Y1969I0J1969D01*
G01Y10560D01*
G01X51583D02*
Y1969D01*
G03X53551Y0I1968J0D01*
G01X319693D01*
G03X321661Y1969I0J1969D01*
G01Y10560D01*
G01X51583D02*
Y1969D01*
G03X53551Y0I1968J0D01*
G01X319693D01*
G03X321661Y1969I0J1969D01*
G01Y10560D01*
G01X51583D02*
Y1969D01*
G03X53551Y0I1968J0D01*
G01X319693D01*
G03X321661Y1969I0J1969D01*
G01Y10560D01*
G01X51583D02*
Y1969D01*
G03X53551Y0I1968J0D01*
G01X319693D01*
G03X321661Y1969I0J1969D01*
G01Y10560D01*
G01X51583D02*
Y1969D01*
G03X53551Y0I1968J0D01*
G01X319693D01*
G03X321661Y1969I0J1969D01*
G01Y10560D01*
G01X51583D02*
Y1969D01*
G03X53551Y0I1968J0D01*
G01X319693D01*
G03X321661Y1969I0J1969D01*
G01Y10560D01*
G01X51583D02*
Y1969D01*
G03X53551Y0I1968J0D01*
G01X319693D01*
G03X321661Y1969I0J1969D01*
G01Y10560D01*
G01X51583D02*
Y1969D01*
G03X53551Y0I1968J0D01*
G01X319693D01*
G03X321661Y1969I0J1969D01*
G01Y10560D01*
G01X51583D02*
Y1969D01*
G03X53551Y0I1968J0D01*
G01X319693D01*
G03X321661Y1969I0J1969D01*
G01Y10560D01*
G01X51583D02*
Y1969D01*
G03X53551Y0I1968J0D01*
G01X319693D01*
G03X321661Y1969I0J1969D01*
G01Y10560D01*
G01X51583D02*
Y1969D01*
G03X53551Y0I1968J0D01*
G01X319693D01*
G03X321661Y1969I0J1969D01*
G01Y10560D01*
G01X367623Y1791450D02*
X217811D01*
G03X209937Y1783576I0J-7874D01*
G01Y1755866D01*
G02X202063Y1747992I-7874J0D01*
G01X70690D01*
G01X93916D02*
G02Y1740118I0J-3937D01*
G01X113602Y1747992D02*
G03Y1740118I0J-3937D01*
G01X191000Y-560138D02*
Y-635138D01*
G01Y-610138D02*
X294000D01*
Y-585138D01*
G01X191000D02*
X294000D01*
G01X296000Y-560138D02*
Y-635138D01*
G01X294000Y-560138D02*
Y-635138D01*
G01X301507Y-620138D02*
Y-615138D01*
X302773D01*
X303280Y-615388D01*
X303660Y-615721D01*
X303977Y-616221D01*
X304230Y-616805D01*
X304293Y-617638D01*
X304230Y-618471D01*
X303977Y-619055D01*
X303660Y-619555D01*
X303280Y-619888D01*
X302773Y-620138D01*
X301507D01*
G01X306417D02*
X308000Y-615138D01*
X309583Y-620138D01*
G01X309013Y-618388D02*
X306987D01*
G01X313100Y-615138D02*
Y-620138D01*
G01X311643Y-615138D02*
X314557D01*
G01X319467Y-620138D02*
X316933D01*
Y-615138D01*
X319467D01*
G01X318453Y-617555D02*
X316933D01*
G01X323300Y-620305D02*
X323173Y-620221D01*
Y-620055D01*
X323300Y-619971D01*
X323427Y-620055D01*
Y-620221D01*
X323300Y-620305D01*
G01Y-618055D02*
X323173Y-617971D01*
Y-617805D01*
X323300Y-617721D01*
X323427Y-617805D01*
Y-617971D01*
X323300Y-618055D01*
G01X296000Y-610138D02*
X496000D01*
G01X301633Y-595138D02*
Y-590138D01*
X303153D01*
X303660Y-590388D01*
X304040Y-590971D01*
X304167Y-591638D01*
X304040Y-592305D01*
X303723Y-592805D01*
X303153Y-593055D01*
X301633D01*
G01X306860Y-595305D02*
X309140Y-590138D01*
G01X311643Y-595138D02*
Y-590138D01*
X314557Y-595138D01*
Y-590138D01*
G01X318200Y-595305D02*
X318073Y-595221D01*
Y-595055D01*
X318200Y-594971D01*
X318327Y-595055D01*
Y-595221D01*
X318200Y-595305D01*
G01Y-593055D02*
X318073Y-592971D01*
Y-592805D01*
X318200Y-592721D01*
X318327Y-592805D01*
Y-592971D01*
X318200Y-593055D01*
G01X296000Y-585138D02*
X496000D01*
G01X301633Y-570138D02*
Y-565138D01*
X303153D01*
X303660Y-565388D01*
X304040Y-565971D01*
X304167Y-566638D01*
X304040Y-567305D01*
X303723Y-567805D01*
X303153Y-568055D01*
X301633D01*
G01X306733Y-570138D02*
Y-565138D01*
X308317D01*
X308823Y-565388D01*
X309140Y-565721D01*
X309267Y-566388D01*
X309140Y-567055D01*
X308760Y-567471D01*
X308317Y-567721D01*
X306733D01*
G01X308317D02*
X309267Y-570138D01*
G01X313100D02*
X312593Y-570055D01*
X312150Y-569721D01*
X311770Y-569221D01*
X311517Y-568638D01*
X311390Y-567971D01*
Y-567305D01*
X311517Y-566638D01*
X311770Y-566055D01*
X312150Y-565555D01*
X312593Y-565221D01*
X313100Y-565138D01*
X313607Y-565221D01*
X314050Y-565555D01*
X314430Y-566055D01*
X314683Y-566638D01*
X314810Y-567305D01*
Y-567971D01*
X314683Y-568638D01*
X314430Y-569221D01*
X314050Y-569721D01*
X313607Y-570055D01*
X313100Y-570138D01*
G01X316933Y-569138D02*
X317250Y-569638D01*
X317630Y-569971D01*
X318073Y-570138D01*
X318580Y-569971D01*
X318960Y-569638D01*
X319340Y-569138D01*
X319467Y-568471D01*
Y-565138D01*
G01X324567Y-570138D02*
X322033D01*
Y-565138D01*
X324567D01*
G01X323553Y-567555D02*
X322033D01*
G01X329793Y-565555D02*
X329413Y-565305D01*
X328970Y-565138D01*
X328463D01*
X327893Y-565388D01*
X327450Y-565805D01*
X327133Y-566305D01*
X326880Y-567138D01*
X326817Y-567888D01*
X326943Y-568638D01*
X327133Y-569138D01*
X327513Y-569638D01*
X327957Y-569971D01*
X328400Y-570138D01*
X328843D01*
X329287Y-569971D01*
X329667Y-569721D01*
X329983Y-569388D01*
G01X333500Y-565138D02*
Y-570138D01*
G01X332043Y-565138D02*
X334957D01*
G01X338600Y-570305D02*
X338473Y-570221D01*
Y-570055D01*
X338600Y-569971D01*
X338727Y-570055D01*
Y-570221D01*
X338600Y-570305D01*
G01Y-568055D02*
X338473Y-567971D01*
Y-567805D01*
X338600Y-567721D01*
X338727Y-567805D01*
Y-567971D01*
X338600Y-568055D01*
G01X321661Y20397D02*
Y38504D01*
G01Y20397D02*
Y38504D01*
G02X329535Y46378I7874J0D01*
G01X321661Y20397D02*
Y38504D01*
G02X329535Y46378I7874J0D01*
G01X488591D01*
G01X321661Y20397D02*
Y38504D01*
G02X329535Y46378I7874J0D01*
G01X488591D01*
G02X496465Y38504I0J-7874D01*
G01X321661Y20397D02*
Y38504D01*
G02X329535Y46378I7874J0D01*
G01X488591D01*
G02X496465Y38504I0J-7874D01*
G01Y35150D01*
G01X321661Y20397D02*
Y38504D01*
G02X329535Y46378I7874J0D01*
G01X488591D01*
G02X496465Y38504I0J-7874D01*
G01Y35150D01*
G01X321661Y20397D02*
Y38504D01*
G02X329535Y46378I7874J0D01*
G01X488591D01*
G02X496465Y38504I0J-7874D01*
G01Y35150D01*
G01X321661Y20397D02*
Y38504D01*
G02X329535Y46378I7874J0D01*
G01X488591D01*
G02X496465Y38504I0J-7874D01*
G01Y35150D01*
G01X321661Y20397D02*
Y38504D01*
G02X329535Y46378I7874J0D01*
G01X488591D01*
G02X496465Y38504I0J-7874D01*
G01Y35150D01*
G01X321661Y20397D02*
Y38504D01*
G02X329535Y46378I7874J0D01*
G01X488591D01*
G02X496465Y38504I0J-7874D01*
G01Y35150D01*
G01X321661Y20397D02*
Y38504D01*
G02X329535Y46378I7874J0D01*
G01X488591D01*
G02X496465Y38504I0J-7874D01*
G01Y35150D01*
G01X321661Y20397D02*
Y38504D01*
G02X329535Y46378I7874J0D01*
G01X488591D01*
G02X496465Y38504I0J-7874D01*
G01Y35150D01*
G01X321661Y20397D02*
Y38504D01*
G02X329535Y46378I7874J0D01*
G01X488591D01*
G02X496465Y38504I0J-7874D01*
G01Y35150D01*
G01X321661Y20397D02*
Y38504D01*
G02X329535Y46378I7874J0D01*
G01X488591D01*
G02X496465Y38504I0J-7874D01*
G01Y35150D01*
G01X321661Y20397D02*
Y38504D01*
G02X329535Y46378I7874J0D01*
G01X488591D01*
G02X496465Y38504I0J-7874D01*
G01Y35150D01*
G01X321661Y20397D02*
Y38504D01*
G02X329535Y46378I7874J0D01*
G01X488591D01*
G02X496465Y38504I0J-7874D01*
G01Y35150D01*
G01X321661Y20397D02*
Y38504D01*
G02X329535Y46378I7874J0D01*
G01X488591D01*
G02X496465Y38504I0J-7874D01*
G01Y35150D01*
G01X321661Y20397D02*
Y38504D01*
G02X329535Y46378I7874J0D01*
G01X488591D01*
G02X496465Y38504I0J-7874D01*
G01Y35150D01*
G01X321661Y20397D02*
Y38504D01*
G02X329535Y46378I7874J0D01*
G01X488591D01*
G02X496465Y38504I0J-7874D01*
G01Y35150D01*
G01X321661Y20397D02*
Y38504D01*
G02X329535Y46378I7874J0D01*
G01X488591D01*
G02X496465Y38504I0J-7874D01*
G01Y35150D01*
G01X321661Y20397D02*
Y38504D01*
G02X329535Y46378I7874J0D01*
G01X488591D01*
G02X496465Y38504I0J-7874D01*
G01Y35150D01*
G01X321661Y20397D02*
Y38504D01*
G02X329535Y46378I7874J0D01*
G01X488591D01*
G02X496465Y38504I0J-7874D01*
G01Y35150D01*
G01X321661Y20397D02*
Y38504D01*
G02X329535Y46378I7874J0D01*
G01X488591D01*
G02X496465Y38504I0J-7874D01*
G01Y35150D01*
G01X321661Y20397D02*
Y38504D01*
G02X329535Y46378I7874J0D01*
G01X488591D01*
G02X496465Y38504I0J-7874D01*
G01Y35150D01*
G01X321661Y20397D02*
Y38504D01*
G02X329535Y46378I7874J0D01*
G01X488591D01*
G02X496465Y38504I0J-7874D01*
G01Y35150D01*
G01X321661Y20397D02*
Y38504D01*
G02X329535Y46378I7874J0D01*
G01X488591D01*
G02X496465Y38504I0J-7874D01*
G01Y35150D01*
G01X321661Y20397D02*
Y38504D01*
G02X329535Y46378I7874J0D01*
G01X488591D01*
G02X496465Y38504I0J-7874D01*
G01Y35150D01*
G01X321661Y20397D02*
Y38504D01*
G02X329535Y46378I7874J0D01*
G01X488591D01*
G02X496465Y38504I0J-7874D01*
G01Y35150D01*
G01X321661Y20397D02*
Y38504D01*
G02X329535Y46378I7874J0D01*
G01X488591D01*
G02X496465Y38504I0J-7874D01*
G01Y35150D01*
G01X321661Y20397D02*
Y38504D01*
G02X329535Y46378I7874J0D01*
G01X488591D01*
G02X496465Y38504I0J-7874D01*
G01Y35150D01*
G01X321661Y20397D02*
Y38504D01*
G02X329535Y46378I7874J0D01*
G01X488591D01*
G02X496465Y38504I0J-7874D01*
G01Y35150D01*
G01X321661Y20397D02*
Y38504D01*
G02X329535Y46378I7874J0D01*
G01X488591D01*
G02X496465Y38504I0J-7874D01*
G01Y35150D01*
G01X321661Y20397D02*
Y38504D01*
G02X329535Y46378I7874J0D01*
G01X488591D01*
G02X496465Y38504I0J-7874D01*
G01Y35150D01*
G01X321661Y20397D02*
Y38504D01*
G02X329535Y46378I7874J0D01*
G01X488591D01*
G02X496465Y38504I0J-7874D01*
G01Y35150D01*
G01X321661Y20397D02*
Y38504D01*
G02X329535Y46378I7874J0D01*
G01X488591D01*
G02X496465Y38504I0J-7874D01*
G01Y35150D01*
G01X321661Y20397D02*
Y38504D01*
G02X329535Y46378I7874J0D01*
G01X488591D01*
G02X496465Y38504I0J-7874D01*
G01Y35150D01*
G01X321661Y20397D02*
Y38504D01*
G02X329535Y46378I7874J0D01*
G01X488591D01*
G02X496465Y38504I0J-7874D01*
G01Y35150D01*
G01X321661Y20397D02*
Y38504D01*
G02X329535Y46378I7874J0D01*
G01X488591D01*
G02X496465Y38504I0J-7874D01*
G01Y35150D01*
G01X321661Y20397D02*
Y38504D01*
G02X329535Y46378I7874J0D01*
G01X488591D01*
G02X496465Y38504I0J-7874D01*
G01Y35150D01*
G01X321661Y20397D02*
Y38504D01*
G02X329535Y46378I7874J0D01*
G01X488591D01*
G02X496465Y38504I0J-7874D01*
G01Y35150D01*
G01X321661Y20397D02*
Y38504D01*
G02X329535Y46378I7874J0D01*
G01X488591D01*
G02X496465Y38504I0J-7874D01*
G01Y35150D01*
G01X321661Y20397D02*
Y38504D01*
G02X329535Y46378I7874J0D01*
G01X488591D01*
G02X496465Y38504I0J-7874D01*
G01Y35150D01*
G01X321661Y20397D02*
Y38504D01*
G02X329535Y46378I7874J0D01*
G01X488591D01*
G02X496465Y38504I0J-7874D01*
G01Y35150D01*
G01X321661Y20397D02*
Y38504D01*
G02X329535Y46378I7874J0D01*
G01X488591D01*
G02X496465Y38504I0J-7874D01*
G01Y35150D01*
G01X321661Y20397D02*
Y38504D01*
G02X329535Y46378I7874J0D01*
G01X488591D01*
G02X496465Y38504I0J-7874D01*
G01Y35150D01*
G01X321661Y20397D02*
Y38504D01*
G02X329535Y46378I7874J0D01*
G01X488591D01*
G02X496465Y38504I0J-7874D01*
G01Y35150D01*
G01X321661Y20397D02*
Y38504D01*
G02X329535Y46378I7874J0D01*
G01X488591D01*
G02X496465Y38504I0J-7874D01*
G01Y35150D01*
G01X321661Y20397D02*
Y38504D01*
G02X329535Y46378I7874J0D01*
G01X488591D01*
G02X496465Y38504I0J-7874D01*
G01Y35150D01*
G01X321661Y20397D02*
Y38504D01*
G02X329535Y46378I7874J0D01*
G01X488591D01*
G02X496465Y38504I0J-7874D01*
G01Y35150D01*
G01X321661Y20397D02*
Y38504D01*
G02X329535Y46378I7874J0D01*
G01X488591D01*
G02X496465Y38504I0J-7874D01*
G01Y35150D01*
G01X321661Y20397D02*
Y38504D01*
G02X329535Y46378I7874J0D01*
G01X488591D01*
G02X496465Y38504I0J-7874D01*
G01Y35150D01*
G01X321661Y20397D02*
Y38504D01*
G02X329535Y46378I7874J0D01*
G01X488591D01*
G02X496465Y38504I0J-7874D01*
G01Y35150D01*
G01X321661Y20397D02*
Y38504D01*
G02X329535Y46378I7874J0D01*
G01X488591D01*
G02X496465Y38504I0J-7874D01*
G01Y35150D01*
G01X321661Y20397D02*
Y38504D01*
G02X329535Y46378I7874J0D01*
G01X488591D01*
G02X496465Y38504I0J-7874D01*
G01Y35150D01*
G01X321661Y20397D02*
Y38504D01*
G02X329535Y46378I7874J0D01*
G01X488591D01*
G02X496465Y38504I0J-7874D01*
G01Y35150D01*
G01X321661Y20397D02*
Y38504D01*
G01Y20397D02*
Y38504D01*
G02X329535Y46378I7874J0D01*
G01X321661Y20397D02*
Y38504D01*
G02X329535Y46378I7874J0D01*
G01X488591D01*
G01X321661Y20397D02*
Y38504D01*
G02X329535Y46378I7874J0D01*
G01X488591D01*
G02X496465Y38504I0J-7874D01*
G01X321661Y20397D02*
Y38504D01*
G02X329535Y46378I7874J0D01*
G01X488591D01*
G02X496465Y38504I0J-7874D01*
G01Y35150D01*
G01X321661Y20397D02*
Y38504D01*
G02X329535Y46378I7874J0D01*
G01X488591D01*
G02X496465Y38504I0J-7874D01*
G01Y35150D01*
G01X321661Y20397D02*
Y38504D01*
G02X329535Y46378I7874J0D01*
G01X488591D01*
G02X496465Y38504I0J-7874D01*
G01Y35150D01*
G01X321661Y20397D02*
Y38504D01*
G02X329535Y46378I7874J0D01*
G01X488591D01*
G02X496465Y38504I0J-7874D01*
G01Y35150D01*
G01X321661Y20397D02*
Y38504D01*
G02X329535Y46378I7874J0D01*
G01X488591D01*
G02X496465Y38504I0J-7874D01*
G01Y35150D01*
G01X321661Y20397D02*
Y38504D01*
G02X329535Y46378I7874J0D01*
G01X488591D01*
G02X496465Y38504I0J-7874D01*
G01Y35150D01*
G01X321661Y20397D02*
Y38504D01*
G02X329535Y46378I7874J0D01*
G01X488591D01*
G02X496465Y38504I0J-7874D01*
G01Y35150D01*
G01X321661Y20397D02*
Y38504D01*
G02X329535Y46378I7874J0D01*
G01X488591D01*
G02X496465Y38504I0J-7874D01*
G01Y35150D01*
G01X321661Y20397D02*
Y38504D01*
G02X329535Y46378I7874J0D01*
G01X488591D01*
G02X496465Y38504I0J-7874D01*
G01Y35150D01*
G01X321661Y20397D02*
Y38504D01*
G02X329535Y46378I7874J0D01*
G01X488591D01*
G02X496465Y38504I0J-7874D01*
G01Y35150D01*
G01X321661Y20397D02*
Y38504D01*
G02X329535Y46378I7874J0D01*
G01X488591D01*
G02X496465Y38504I0J-7874D01*
G01Y35150D01*
G01X321661Y20397D02*
Y38504D01*
G02X329535Y46378I7874J0D01*
G01X488591D01*
G02X496465Y38504I0J-7874D01*
G01Y35150D01*
G01X321661Y20397D02*
Y38504D01*
G02X329535Y46378I7874J0D01*
G01X488591D01*
G02X496465Y38504I0J-7874D01*
G01Y35150D01*
G01X321661Y20397D02*
Y38504D01*
G02X329535Y46378I7874J0D01*
G01X488591D01*
G02X496465Y38504I0J-7874D01*
G01Y35150D01*
G01X321661Y20397D02*
Y38504D01*
G02X329535Y46378I7874J0D01*
G01X488591D01*
G02X496465Y38504I0J-7874D01*
G01Y35150D01*
G01X321661Y20397D02*
Y38504D01*
G02X329535Y46378I7874J0D01*
G01X488591D01*
G02X496465Y38504I0J-7874D01*
G01Y35150D01*
G01X321661Y20397D02*
Y38504D01*
G02X329535Y46378I7874J0D01*
G01X488591D01*
G02X496465Y38504I0J-7874D01*
G01Y35150D01*
G01X321661Y20397D02*
Y38504D01*
G02X329535Y46378I7874J0D01*
G01X488591D01*
G02X496465Y38504I0J-7874D01*
G01Y35150D01*
G01X321661Y20397D02*
Y38504D01*
G02X329535Y46378I7874J0D01*
G01X488591D01*
G02X496465Y38504I0J-7874D01*
G01Y35150D01*
G01X321661Y20397D02*
Y38504D01*
G02X329535Y46378I7874J0D01*
G01X488591D01*
G02X496465Y38504I0J-7874D01*
G01Y35150D01*
G01X321661Y20397D02*
Y38504D01*
G02X329535Y46378I7874J0D01*
G01X488591D01*
G02X496465Y38504I0J-7874D01*
G01Y35150D01*
G01X321661Y20397D02*
Y38504D01*
G02X329535Y46378I7874J0D01*
G01X488591D01*
G02X496465Y38504I0J-7874D01*
G01Y35150D01*
G01X321661Y20397D02*
Y38504D01*
G02X329535Y46378I7874J0D01*
G01X488591D01*
G02X496465Y38504I0J-7874D01*
G01Y35150D01*
G01X321661Y20397D02*
Y38504D01*
G02X329535Y46378I7874J0D01*
G01X488591D01*
G02X496465Y38504I0J-7874D01*
G01Y35150D01*
G01X321661Y20397D02*
Y38504D01*
G02X329535Y46378I7874J0D01*
G01X488591D01*
G02X496465Y38504I0J-7874D01*
G01Y35150D01*
G01X321661Y20397D02*
Y38504D01*
G02X329535Y46378I7874J0D01*
G01X488591D01*
G02X496465Y38504I0J-7874D01*
G01Y35150D01*
G01X321661Y20397D02*
Y38504D01*
G02X329535Y46378I7874J0D01*
G01X488591D01*
G02X496465Y38504I0J-7874D01*
G01Y35150D01*
G01X321661Y20397D02*
Y38504D01*
G02X329535Y46378I7874J0D01*
G01X488591D01*
G02X496465Y38504I0J-7874D01*
G01Y35150D01*
G01X321661Y20397D02*
Y38504D01*
G02X329535Y46378I7874J0D01*
G01X488591D01*
G02X496465Y38504I0J-7874D01*
G01Y35150D01*
G01X321661Y20397D02*
Y38504D01*
G02X329535Y46378I7874J0D01*
G01X488591D01*
G02X496465Y38504I0J-7874D01*
G01Y35150D01*
G01X321661Y20397D02*
Y38504D01*
G02X329535Y46378I7874J0D01*
G01X488591D01*
G02X496465Y38504I0J-7874D01*
G01Y35150D01*
G01X321661Y20397D02*
Y38504D01*
G02X329535Y46378I7874J0D01*
G01X488591D01*
G02X496465Y38504I0J-7874D01*
G01Y35150D01*
G01X321661Y20397D02*
Y38504D01*
G02X329535Y46378I7874J0D01*
G01X488591D01*
G02X496465Y38504I0J-7874D01*
G01Y35150D01*
G01X321661Y20397D02*
Y38504D01*
G02X329535Y46378I7874J0D01*
G01X488591D01*
G02X496465Y38504I0J-7874D01*
G01Y35150D01*
G01X321661Y20397D02*
Y38504D01*
G02X329535Y46378I7874J0D01*
G01X488591D01*
G02X496465Y38504I0J-7874D01*
G01Y35150D01*
G01X321661Y20397D02*
Y38504D01*
G02X329535Y46378I7874J0D01*
G01X488591D01*
G02X496465Y38504I0J-7874D01*
G01Y35150D01*
G01X321661Y20397D02*
Y38504D01*
G02X329535Y46378I7874J0D01*
G01X488591D01*
G02X496465Y38504I0J-7874D01*
G01Y35150D01*
G01X321661Y20397D02*
Y38504D01*
G02X329535Y46378I7874J0D01*
G01X488591D01*
G02X496465Y38504I0J-7874D01*
G01Y35150D01*
G01X321661Y20397D02*
Y38504D01*
G02X329535Y46378I7874J0D01*
G01X488591D01*
G02X496465Y38504I0J-7874D01*
G01Y35150D01*
G01X321661Y20397D02*
Y38504D01*
G02X329535Y46378I7874J0D01*
G01X488591D01*
G02X496465Y38504I0J-7874D01*
G01Y35150D01*
G01X321661Y20397D02*
Y38504D01*
G02X329535Y46378I7874J0D01*
G01X488591D01*
G02X496465Y38504I0J-7874D01*
G01Y35150D01*
G01X321661Y20397D02*
Y38504D01*
G02X329535Y46378I7874J0D01*
G01X488591D01*
G02X496465Y38504I0J-7874D01*
G01Y35150D01*
G01X321661Y20397D02*
Y38504D01*
G02X329535Y46378I7874J0D01*
G01X488591D01*
G02X496465Y38504I0J-7874D01*
G01Y35150D01*
G01X321661Y20397D02*
Y38504D01*
G02X329535Y46378I7874J0D01*
G01X488591D01*
G02X496465Y38504I0J-7874D01*
G01Y35150D01*
G01X321661Y20397D02*
Y38504D01*
G02X329535Y46378I7874J0D01*
G01X488591D01*
G02X496465Y38504I0J-7874D01*
G01Y35150D01*
G01X321661Y20397D02*
Y38504D01*
G02X329535Y46378I7874J0D01*
G01X488591D01*
G02X496465Y38504I0J-7874D01*
G01Y35150D01*
G01X321661Y20397D02*
Y38504D01*
G02X329535Y46378I7874J0D01*
G01X488591D01*
G02X496465Y38504I0J-7874D01*
G01Y35150D01*
G01X321661Y20397D02*
Y38504D01*
G02X329535Y46378I7874J0D01*
G01X488591D01*
G02X496465Y38504I0J-7874D01*
G01Y35150D01*
G01X321661Y20397D02*
Y38504D01*
G02X329535Y46378I7874J0D01*
G01X488591D01*
G02X496465Y38504I0J-7874D01*
G01Y35150D01*
G01X321661Y20397D02*
Y38504D01*
G02X329535Y46378I7874J0D01*
G01X488591D01*
G02X496465Y38504I0J-7874D01*
G01Y35150D01*
G01X375497Y1755866D02*
Y1783576D01*
G01Y1755866D02*
G03X383371Y1747992I7874J0D01*
G01X415054D01*
G03X422928Y1755866I0J7874D01*
G01X367623Y1791450D02*
G02X375497Y1783576I0J-7874D01*
G01X381484Y46378D02*
G02Y38504I0J-3937D01*
G01X390803Y1747992D02*
G02Y1740118I0J-3937D01*
G01X401170Y46378D02*
G03Y38504I0J-3937D01*
G01X410489Y1747992D02*
G03Y1740118I0J-3937D01*
G01X411000Y-610138D02*
Y-635138D01*
G01X413633Y-612638D02*
Y-617638D01*
X416167D01*
G01X419240Y-612638D02*
X420760D01*
G01X420000D02*
Y-617638D01*
G01X419240D02*
X420760D01*
G01X425607Y-614971D02*
X425860Y-614721D01*
X426050Y-614305D01*
X426177Y-613721D01*
X426050Y-613221D01*
X425797Y-612888D01*
X425353Y-612638D01*
X423643D01*
Y-617638D01*
X425733D01*
X426177Y-617305D01*
X426430Y-616805D01*
X426557Y-616221D01*
X426430Y-615638D01*
X426050Y-615138D01*
X425607Y-614971D01*
X423643D01*
G01X430200Y-617805D02*
X430073Y-617721D01*
Y-617555D01*
X430200Y-617471D01*
X430327Y-617555D01*
Y-617721D01*
X430200Y-617805D01*
G01Y-615555D02*
X430073Y-615471D01*
Y-615305D01*
X430200Y-615221D01*
X430327Y-615305D01*
Y-615471D01*
X430200Y-615555D01*
G01X422928Y1783576D02*
Y1755866D01*
G01Y1783576D02*
G02X430802Y1791450I7874J0D01*
G01X631796D01*
G02X639670Y1783576I0J-7874D01*
G01Y1755866D01*
G03X647544Y1747992I7874J0D01*
G01X760350D01*
G03X768224Y1755866I0J7874D01*
G01Y1783576D01*
G02X776098Y1791450I7874J0D01*
G01X1081462D01*
G02X1089336Y1783576I0J-7874D01*
G01Y1755866D01*
G03X1097210Y1747992I7874J0D01*
G01X1209937D01*
G03X1217811Y1755866I0J7874D01*
G01Y1783576D01*
G02X1225685Y1791450I7874J0D01*
G01X1426678D01*
G02X1434552Y1783576I0J-7874D01*
G01X454000Y-610138D02*
Y-635138D01*
G01Y-585138D02*
Y-610138D01*
G01X459013Y-637305D02*
X459120Y-637180D01*
X459200Y-636971D01*
X459253Y-636680D01*
X459200Y-636430D01*
X459093Y-636263D01*
X458907Y-636138D01*
X458187D01*
Y-638638D01*
X459067D01*
X459253Y-638471D01*
X459360Y-638221D01*
X459413Y-637930D01*
X459360Y-637638D01*
X459200Y-637388D01*
X459013Y-637305D01*
X458187D01*
G01X461480Y-638638D02*
Y-636971D01*
G01Y-637263D02*
X461373Y-637096D01*
X461213Y-637013D01*
X461027Y-636971D01*
X460840Y-637055D01*
X460680Y-637221D01*
X460573Y-637471D01*
X460520Y-637805D01*
X460573Y-638138D01*
X460680Y-638388D01*
X460840Y-638555D01*
X461027Y-638638D01*
X461213Y-638596D01*
X461373Y-638471D01*
X461480Y-638305D01*
G01X462800Y-638346D02*
X462933Y-638513D01*
X463120Y-638638D01*
X463280D01*
X463440Y-638555D01*
X463547Y-638430D01*
X463600Y-638263D01*
X463573Y-638013D01*
X463467Y-637888D01*
X462987Y-637638D01*
X462880Y-637346D01*
X462933Y-637138D01*
X463040Y-637013D01*
X463200Y-636971D01*
X463360Y-637013D01*
X463520Y-637138D01*
G01X465000Y-637513D02*
X465853D01*
X465773Y-637221D01*
X465640Y-637055D01*
X465453Y-636971D01*
X465267Y-637013D01*
X465107Y-637138D01*
X465000Y-637430D01*
X464947Y-637680D01*
Y-637930D01*
X465000Y-638180D01*
X465133Y-638430D01*
X465293Y-638596D01*
X465480Y-638638D01*
X465667Y-638555D01*
X465853Y-638305D01*
G01X467120Y-638638D02*
Y-636138D01*
G01Y-637388D02*
X467253Y-637138D01*
X467413Y-637013D01*
X467573Y-636971D01*
X467813Y-637055D01*
X467973Y-637221D01*
X468080Y-637513D01*
Y-637846D01*
X468027Y-638180D01*
X467920Y-638430D01*
X467733Y-638596D01*
X467573Y-638638D01*
X467413Y-638596D01*
X467253Y-638471D01*
X467120Y-638263D01*
G01X469800Y-638638D02*
X469640Y-638596D01*
X469480Y-638430D01*
X469373Y-638138D01*
X469320Y-637805D01*
X469373Y-637471D01*
X469480Y-637180D01*
X469640Y-637013D01*
X469800Y-636971D01*
X469960Y-637013D01*
X470120Y-637180D01*
X470227Y-637471D01*
X470253Y-637805D01*
X470227Y-638138D01*
X470120Y-638430D01*
X469960Y-638596D01*
X469800Y-638638D01*
G01X472480D02*
Y-636971D01*
G01Y-637263D02*
X472373Y-637096D01*
X472213Y-637013D01*
X472027Y-636971D01*
X471840Y-637055D01*
X471680Y-637221D01*
X471573Y-637471D01*
X471520Y-637805D01*
X471573Y-638138D01*
X471680Y-638388D01*
X471840Y-638555D01*
X472027Y-638638D01*
X472213Y-638596D01*
X472373Y-638471D01*
X472480Y-638305D01*
G01X473827Y-638638D02*
Y-636971D01*
G01Y-637305D02*
X473960Y-637138D01*
X474093Y-637013D01*
X474280Y-636971D01*
X474413Y-637013D01*
X474573Y-637138D01*
G01X476880Y-636138D02*
Y-638638D01*
G01Y-638263D02*
X476773Y-638471D01*
X476613Y-638596D01*
X476427Y-638638D01*
X476213Y-638555D01*
X476053Y-638346D01*
X475947Y-638096D01*
X475920Y-637805D01*
X475947Y-637513D01*
X476053Y-637263D01*
X476213Y-637055D01*
X476427Y-636971D01*
X476613Y-637013D01*
X476747Y-637096D01*
X476880Y-637263D01*
G01X480267Y-638638D02*
Y-636138D01*
X480933D01*
X481147Y-636263D01*
X481280Y-636430D01*
X481333Y-636763D01*
X481280Y-637096D01*
X481120Y-637305D01*
X480933Y-637430D01*
X480267D01*
G01X480933D02*
X481333Y-638638D01*
G01X482600Y-637513D02*
X483453D01*
X483373Y-637221D01*
X483240Y-637055D01*
X483053Y-636971D01*
X482867Y-637013D01*
X482707Y-637138D01*
X482600Y-637430D01*
X482547Y-637680D01*
Y-637930D01*
X482600Y-638180D01*
X482733Y-638430D01*
X482893Y-638596D01*
X483080Y-638638D01*
X483267Y-638555D01*
X483453Y-638305D01*
G01X484720Y-636971D02*
X485200Y-638638D01*
X485680Y-636971D01*
G01X487400Y-638721D02*
X487347Y-638680D01*
Y-638596D01*
X487400Y-638555D01*
X487453Y-638596D01*
Y-638680D01*
X487400Y-638721D01*
G01X489147Y-638346D02*
X489333Y-638555D01*
X489547Y-638638D01*
X489760Y-638555D01*
X489947Y-638305D01*
X490080Y-637930D01*
X490133Y-637555D01*
Y-637096D01*
X490080Y-636721D01*
X489947Y-636388D01*
X489787Y-636221D01*
X489600Y-636138D01*
X489387Y-636221D01*
X489227Y-636388D01*
X489120Y-636638D01*
X489067Y-636971D01*
X489120Y-637263D01*
X489253Y-637555D01*
X489413Y-637721D01*
X489600Y-637763D01*
X489813Y-637680D01*
X489973Y-637471D01*
X490133Y-637096D01*
G01X492013Y-637305D02*
X492120Y-637180D01*
X492200Y-636971D01*
X492253Y-636680D01*
X492200Y-636430D01*
X492093Y-636263D01*
X491907Y-636138D01*
X491187D01*
Y-638638D01*
X492067D01*
X492253Y-638471D01*
X492360Y-638221D01*
X492413Y-637930D01*
X492360Y-637638D01*
X492200Y-637388D01*
X492013Y-637305D01*
X491187D01*
G01X457900Y-612638D02*
Y-617638D01*
G01X456443Y-612638D02*
X459357D01*
G01X463000Y-617638D02*
X462620Y-617555D01*
X462240Y-617221D01*
X461987Y-616638D01*
X461860Y-615971D01*
X461987Y-615305D01*
X462240Y-614721D01*
X462620Y-614388D01*
X463000Y-614305D01*
X463380Y-614388D01*
X463760Y-614721D01*
X464013Y-615305D01*
X464077Y-615971D01*
X464013Y-616638D01*
X463760Y-617221D01*
X463380Y-617555D01*
X463000Y-617638D01*
G01X468100D02*
X467720Y-617555D01*
X467340Y-617221D01*
X467087Y-616638D01*
X466960Y-615971D01*
X467087Y-615305D01*
X467340Y-614721D01*
X467720Y-614388D01*
X468100Y-614305D01*
X468480Y-614388D01*
X468860Y-614721D01*
X469113Y-615305D01*
X469177Y-615971D01*
X469113Y-616638D01*
X468860Y-617221D01*
X468480Y-617555D01*
X468100Y-617638D01*
G01X473200D02*
Y-612638D01*
G01X478300Y-617805D02*
X478173Y-617721D01*
Y-617555D01*
X478300Y-617471D01*
X478427Y-617555D01*
Y-617721D01*
X478300Y-617805D01*
G01Y-615555D02*
X478173Y-615471D01*
Y-615305D01*
X478300Y-615221D01*
X478427Y-615305D01*
Y-615471D01*
X478300Y-615555D01*
G01X456633Y-592638D02*
Y-587638D01*
X458217D01*
X458723Y-587888D01*
X459040Y-588221D01*
X459167Y-588888D01*
X459040Y-589555D01*
X458660Y-589971D01*
X458217Y-590221D01*
X456633D01*
G01X458217D02*
X459167Y-592638D01*
G01X464267D02*
X461733D01*
Y-587638D01*
X464267D01*
G01X463253Y-590055D02*
X461733D01*
G01X466517Y-587638D02*
X468100Y-592638D01*
X469683Y-587638D01*
G01X473200Y-592805D02*
X473073Y-592721D01*
Y-592555D01*
X473200Y-592471D01*
X473327Y-592555D01*
Y-592721D01*
X473200Y-592805D01*
G01Y-590555D02*
X473073Y-590471D01*
Y-590305D01*
X473200Y-590221D01*
X473327Y-590305D01*
Y-590471D01*
X473200Y-590555D01*
G01X496465Y26024D02*
Y22756D01*
G03X498433Y20787I1968J-1D01*
G01X496465Y26024D02*
Y22756D01*
G03X498433Y20787I1968J-1D01*
G01X764575D01*
G01X496465Y26024D02*
Y22756D01*
G03X498433Y20787I1968J-1D01*
G01X764575D01*
G03X766543Y22756I-1J1969D01*
G01X496465Y26024D02*
Y22756D01*
G03X498433Y20787I1968J-1D01*
G01X764575D01*
G03X766543Y22756I-1J1969D01*
G01Y38504D01*
G02X774417Y46378I7874J0D01*
G01X871260D01*
G03X879134Y54252I0J7874D01*
G01Y134331D01*
G01X496465Y26024D02*
Y22756D01*
G03X498433Y20787I1968J-1D01*
G01X764575D01*
G03X766543Y22756I-1J1969D01*
G01Y26024D01*
G01X496465D02*
Y22756D01*
G03X498433Y20787I1968J-1D01*
G01X764575D01*
G03X766543Y22756I-1J1969D01*
G01Y26024D01*
G01X496465D02*
Y22756D01*
G03X498433Y20787I1968J-1D01*
G01X764575D01*
G03X766543Y22756I-1J1969D01*
G01Y26024D01*
G01X496465D02*
Y22756D01*
G03X498433Y20787I1968J-1D01*
G01X764575D01*
G03X766543Y22756I-1J1969D01*
G01Y26024D01*
G01X496465D02*
Y22756D01*
G03X498433Y20787I1968J-1D01*
G01X764575D01*
G03X766543Y22756I-1J1969D01*
G01Y26024D01*
G01X496465D02*
Y22756D01*
G03X498433Y20787I1968J-1D01*
G01X764575D01*
G03X766543Y22756I-1J1969D01*
G01Y26024D01*
G01X496465D02*
Y22756D01*
G03X498433Y20787I1968J-1D01*
G01X764575D01*
G03X766543Y22756I-1J1969D01*
G01Y26024D01*
G01X496465D02*
Y22756D01*
G03X498433Y20787I1968J-1D01*
G01X764575D01*
G03X766543Y22756I-1J1969D01*
G01Y26024D01*
G01X496465D02*
Y22756D01*
G03X498433Y20787I1968J-1D01*
G01X764575D01*
G03X766543Y22756I-1J1969D01*
G01Y26024D01*
G01X496465D02*
Y22756D01*
G03X498433Y20787I1968J-1D01*
G01X764575D01*
G03X766543Y22756I-1J1969D01*
G01Y26024D01*
G01X496465D02*
Y22756D01*
G03X498433Y20787I1968J-1D01*
G01X764575D01*
G03X766543Y22756I-1J1969D01*
G01Y26024D01*
G01X496465D02*
Y22756D01*
G03X498433Y20787I1968J-1D01*
G01X764575D01*
G03X766543Y22756I-1J1969D01*
G01Y26024D01*
G01X496465D02*
Y22756D01*
G03X498433Y20787I1968J-1D01*
G01X764575D01*
G03X766543Y22756I-1J1969D01*
G01Y26024D01*
G01X496465D02*
Y22756D01*
G03X498433Y20787I1968J-1D01*
G01X764575D01*
G03X766543Y22756I-1J1969D01*
G01Y26024D01*
G01X496465D02*
Y22756D01*
G03X498433Y20787I1968J-1D01*
G01X764575D01*
G03X766543Y22756I-1J1969D01*
G01Y26024D01*
G01X496465D02*
Y22756D01*
G03X498433Y20787I1968J-1D01*
G01X764575D01*
G03X766543Y22756I-1J1969D01*
G01Y26024D01*
G01X496465D02*
Y22756D01*
G03X498433Y20787I1968J-1D01*
G01X764575D01*
G03X766543Y22756I-1J1969D01*
G01Y26024D01*
G01X496465D02*
Y22756D01*
G03X498433Y20787I1968J-1D01*
G01X764575D01*
G03X766543Y22756I-1J1969D01*
G01Y26024D01*
G01X496465D02*
Y22756D01*
G03X498433Y20787I1968J-1D01*
G01X764575D01*
G03X766543Y22756I-1J1969D01*
G01Y26024D01*
G01X496465D02*
Y22756D01*
G03X498433Y20787I1968J-1D01*
G01X764575D01*
G03X766543Y22756I-1J1969D01*
G01Y26024D01*
G01X496465D02*
Y22756D01*
G03X498433Y20787I1968J-1D01*
G01X764575D01*
G03X766543Y22756I-1J1969D01*
G01Y26024D01*
G01X496465D02*
Y22756D01*
G03X498433Y20787I1968J-1D01*
G01X764575D01*
G03X766543Y22756I-1J1969D01*
G01Y26024D01*
G01X496465D02*
Y22756D01*
G03X498433Y20787I1968J-1D01*
G01X764575D01*
G03X766543Y22756I-1J1969D01*
G01Y26024D01*
G01X496465D02*
Y22756D01*
G03X498433Y20787I1968J-1D01*
G01X764575D01*
G03X766543Y22756I-1J1969D01*
G01Y26024D01*
G01X496465D02*
Y22756D01*
G03X498433Y20787I1968J-1D01*
G01X764575D01*
G03X766543Y22756I-1J1969D01*
G01Y26024D01*
G01X496465D02*
Y22756D01*
G03X498433Y20787I1968J-1D01*
G01X764575D01*
G03X766543Y22756I-1J1969D01*
G01Y26024D01*
G01X496465D02*
Y22756D01*
G03X498433Y20787I1968J-1D01*
G01X764575D01*
G03X766543Y22756I-1J1969D01*
G01Y26024D01*
G01X496465D02*
Y22756D01*
G03X498433Y20787I1968J-1D01*
G01X764575D01*
G03X766543Y22756I-1J1969D01*
G01Y26024D01*
G01X496465D02*
Y22756D01*
G03X498433Y20787I1968J-1D01*
G01X764575D01*
G03X766543Y22756I-1J1969D01*
G01Y26024D01*
G01X496465D02*
Y22756D01*
G03X498433Y20787I1968J-1D01*
G01X764575D01*
G03X766543Y22756I-1J1969D01*
G01Y26024D01*
G01X496465D02*
Y22756D01*
G03X498433Y20787I1968J-1D01*
G01X764575D01*
G03X766543Y22756I-1J1969D01*
G01Y26024D01*
G01X496465D02*
Y22756D01*
G03X498433Y20787I1968J-1D01*
G01X764575D01*
G03X766543Y22756I-1J1969D01*
G01Y26024D01*
G01X496465D02*
Y22756D01*
G03X498433Y20787I1968J-1D01*
G01X764575D01*
G03X766543Y22756I-1J1969D01*
G01Y26024D01*
G01X496465D02*
Y22756D01*
G03X498433Y20787I1968J-1D01*
G01X764575D01*
G03X766543Y22756I-1J1969D01*
G01Y26024D01*
G01X496465D02*
Y22756D01*
G03X498433Y20787I1968J-1D01*
G01X764575D01*
G03X766543Y22756I-1J1969D01*
G01Y26024D01*
G01X496465D02*
Y22756D01*
G03X498433Y20787I1968J-1D01*
G01X764575D01*
G03X766543Y22756I-1J1969D01*
G01Y26024D01*
G01X496465D02*
Y22756D01*
G03X498433Y20787I1968J-1D01*
G01X764575D01*
G03X766543Y22756I-1J1969D01*
G01Y26024D01*
G01X496465D02*
Y22756D01*
G03X498433Y20787I1968J-1D01*
G01X764575D01*
G03X766543Y22756I-1J1969D01*
G01Y26024D01*
G01X496465D02*
Y22756D01*
G03X498433Y20787I1968J-1D01*
G01X764575D01*
G03X766543Y22756I-1J1969D01*
G01Y26024D01*
G01X496465D02*
Y22756D01*
G03X498433Y20787I1968J-1D01*
G01X764575D01*
G03X766543Y22756I-1J1969D01*
G01Y26024D01*
G01X496465D02*
Y22756D01*
G03X498433Y20787I1968J-1D01*
G01X764575D01*
G03X766543Y22756I-1J1969D01*
G01Y26024D01*
G01X496465D02*
Y22756D01*
G03X498433Y20787I1968J-1D01*
G01X764575D01*
G03X766543Y22756I-1J1969D01*
G01Y26024D01*
G01X496465D02*
Y22756D01*
G03X498433Y20787I1968J-1D01*
G01X764575D01*
G03X766543Y22756I-1J1969D01*
G01Y26024D01*
G01X496465D02*
Y22756D01*
G03X498433Y20787I1968J-1D01*
G01X764575D01*
G03X766543Y22756I-1J1969D01*
G01Y26024D01*
G01X496465D02*
Y22756D01*
G03X498433Y20787I1968J-1D01*
G01X764575D01*
G03X766543Y22756I-1J1969D01*
G01Y26024D01*
G01X496465D02*
Y22756D01*
G03X498433Y20787I1968J-1D01*
G01X764575D01*
G03X766543Y22756I-1J1969D01*
G01Y26024D01*
G01X496465D02*
Y22756D01*
G01Y26024D02*
Y22756D01*
G03X498433Y20787I1968J-1D01*
G01X496465Y26024D02*
Y22756D01*
G03X498433Y20787I1968J-1D01*
G01X764575D01*
G01X496465Y26024D02*
Y22756D01*
G03X498433Y20787I1968J-1D01*
G01X764575D01*
G03X766543Y22756I-1J1969D01*
G01X496465Y26024D02*
Y22756D01*
G03X498433Y20787I1968J-1D01*
G01X764575D01*
G03X766543Y22756I-1J1969D01*
G01Y26024D01*
G01X496465D02*
Y22756D01*
G03X498433Y20787I1968J-1D01*
G01X764575D01*
G03X766543Y22756I-1J1969D01*
G01Y26024D01*
G01X496465D02*
Y22756D01*
G03X498433Y20787I1968J-1D01*
G01X764575D01*
G03X766543Y22756I-1J1969D01*
G01Y26024D01*
G01X496465D02*
Y22756D01*
G03X498433Y20787I1968J-1D01*
G01X764575D01*
G03X766543Y22756I-1J1969D01*
G01Y26024D01*
G01X496465D02*
Y22756D01*
G03X498433Y20787I1968J-1D01*
G01X764575D01*
G03X766543Y22756I-1J1969D01*
G01Y26024D01*
G01X496465D02*
Y22756D01*
G03X498433Y20787I1968J-1D01*
G01X764575D01*
G03X766543Y22756I-1J1969D01*
G01Y26024D01*
G01X496465D02*
Y22756D01*
G03X498433Y20787I1968J-1D01*
G01X764575D01*
G03X766543Y22756I-1J1969D01*
G01Y26024D01*
G01X496465D02*
Y22756D01*
G03X498433Y20787I1968J-1D01*
G01X764575D01*
G03X766543Y22756I-1J1969D01*
G01Y26024D01*
G01X496465D02*
Y22756D01*
G03X498433Y20787I1968J-1D01*
G01X764575D01*
G03X766543Y22756I-1J1969D01*
G01Y26024D01*
G01X496465D02*
Y22756D01*
G03X498433Y20787I1968J-1D01*
G01X764575D01*
G03X766543Y22756I-1J1969D01*
G01Y26024D01*
G01X496465D02*
Y22756D01*
G03X498433Y20787I1968J-1D01*
G01X764575D01*
G03X766543Y22756I-1J1969D01*
G01Y26024D01*
G01X496465D02*
Y22756D01*
G03X498433Y20787I1968J-1D01*
G01X764575D01*
G03X766543Y22756I-1J1969D01*
G01Y26024D01*
G01X496465D02*
Y22756D01*
G03X498433Y20787I1968J-1D01*
G01X764575D01*
G03X766543Y22756I-1J1969D01*
G01Y26024D01*
G01X496465D02*
Y22756D01*
G03X498433Y20787I1968J-1D01*
G01X764575D01*
G03X766543Y22756I-1J1969D01*
G01Y26024D01*
G01X496465D02*
Y22756D01*
G03X498433Y20787I1968J-1D01*
G01X764575D01*
G03X766543Y22756I-1J1969D01*
G01Y26024D01*
G01X496465D02*
Y22756D01*
G03X498433Y20787I1968J-1D01*
G01X764575D01*
G03X766543Y22756I-1J1969D01*
G01Y26024D01*
G01X496465D02*
Y22756D01*
G03X498433Y20787I1968J-1D01*
G01X764575D01*
G03X766543Y22756I-1J1969D01*
G01Y26024D01*
G01X496465D02*
Y22756D01*
G03X498433Y20787I1968J-1D01*
G01X764575D01*
G03X766543Y22756I-1J1969D01*
G01Y26024D01*
G01X496465D02*
Y22756D01*
G03X498433Y20787I1968J-1D01*
G01X764575D01*
G03X766543Y22756I-1J1969D01*
G01Y26024D01*
G01X496465D02*
Y22756D01*
G03X498433Y20787I1968J-1D01*
G01X764575D01*
G03X766543Y22756I-1J1969D01*
G01Y26024D01*
G01X496465D02*
Y22756D01*
G03X498433Y20787I1968J-1D01*
G01X764575D01*
G03X766543Y22756I-1J1969D01*
G01Y26024D01*
G01X496465D02*
Y22756D01*
G03X498433Y20787I1968J-1D01*
G01X764575D01*
G03X766543Y22756I-1J1969D01*
G01Y26024D01*
G01X496465D02*
Y22756D01*
G03X498433Y20787I1968J-1D01*
G01X764575D01*
G03X766543Y22756I-1J1969D01*
G01Y26024D01*
G01X496465D02*
Y22756D01*
G03X498433Y20787I1968J-1D01*
G01X764575D01*
G03X766543Y22756I-1J1969D01*
G01Y26024D01*
G01X496465D02*
Y22756D01*
G03X498433Y20787I1968J-1D01*
G01X764575D01*
G03X766543Y22756I-1J1969D01*
G01Y26024D01*
G01X496465D02*
Y22756D01*
G03X498433Y20787I1968J-1D01*
G01X764575D01*
G03X766543Y22756I-1J1969D01*
G01Y26024D01*
G01X496465D02*
Y22756D01*
G03X498433Y20787I1968J-1D01*
G01X764575D01*
G03X766543Y22756I-1J1969D01*
G01Y26024D01*
G01X496465D02*
Y22756D01*
G03X498433Y20787I1968J-1D01*
G01X764575D01*
G03X766543Y22756I-1J1969D01*
G01Y26024D01*
G01X496465D02*
Y22756D01*
G03X498433Y20787I1968J-1D01*
G01X764575D01*
G03X766543Y22756I-1J1969D01*
G01Y26024D01*
G01X496465D02*
Y22756D01*
G03X498433Y20787I1968J-1D01*
G01X764575D01*
G03X766543Y22756I-1J1969D01*
G01Y26024D01*
G01X496465D02*
Y22756D01*
G03X498433Y20787I1968J-1D01*
G01X764575D01*
G03X766543Y22756I-1J1969D01*
G01Y26024D01*
G01X496465D02*
Y22756D01*
G03X498433Y20787I1968J-1D01*
G01X764575D01*
G03X766543Y22756I-1J1969D01*
G01Y26024D01*
G01X496465D02*
Y22756D01*
G03X498433Y20787I1968J-1D01*
G01X764575D01*
G03X766543Y22756I-1J1969D01*
G01Y26024D01*
G01X496465D02*
Y22756D01*
G03X498433Y20787I1968J-1D01*
G01X764575D01*
G03X766543Y22756I-1J1969D01*
G01Y26024D01*
G01X496465D02*
Y22756D01*
G03X498433Y20787I1968J-1D01*
G01X764575D01*
G03X766543Y22756I-1J1969D01*
G01Y26024D01*
G01X496465D02*
Y22756D01*
G03X498433Y20787I1968J-1D01*
G01X764575D01*
G03X766543Y22756I-1J1969D01*
G01Y26024D01*
G01X496465D02*
Y22756D01*
G03X498433Y20787I1968J-1D01*
G01X764575D01*
G03X766543Y22756I-1J1969D01*
G01Y26024D01*
G01X496465D02*
Y22756D01*
G03X498433Y20787I1968J-1D01*
G01X764575D01*
G03X766543Y22756I-1J1969D01*
G01Y26024D01*
G01X496465D02*
Y22756D01*
G03X498433Y20787I1968J-1D01*
G01X764575D01*
G03X766543Y22756I-1J1969D01*
G01Y26024D01*
G01X496465D02*
Y22756D01*
G03X498433Y20787I1968J-1D01*
G01X764575D01*
G03X766543Y22756I-1J1969D01*
G01Y26024D01*
G01X496465D02*
Y22756D01*
G03X498433Y20787I1968J-1D01*
G01X764575D01*
G03X766543Y22756I-1J1969D01*
G01Y26024D01*
G01X496465D02*
Y22756D01*
G03X498433Y20787I1968J-1D01*
G01X764575D01*
G03X766543Y22756I-1J1969D01*
G01Y26024D01*
G01X496465D02*
Y22756D01*
G03X498433Y20787I1968J-1D01*
G01X764575D01*
G03X766543Y22756I-1J1969D01*
G01Y26024D01*
G01X496465D02*
Y22756D01*
G03X498433Y20787I1968J-1D01*
G01X764575D01*
G03X766543Y22756I-1J1969D01*
G01Y26024D01*
G01X496465D02*
Y22756D01*
G03X498433Y20787I1968J-1D01*
G01X764575D01*
G03X766543Y22756I-1J1969D01*
G01Y26024D01*
G01X496465D02*
Y22756D01*
G03X498433Y20787I1968J-1D01*
G01X764575D01*
G03X766543Y22756I-1J1969D01*
G01Y26024D01*
G01X496465D02*
Y22756D01*
G03X498433Y20787I1968J-1D01*
G01X764575D01*
G03X766543Y22756I-1J1969D01*
G01Y26024D01*
G01X1289590Y1361034D02*
X689590D01*
Y461034D01*
G01Y967660D02*
X1289590D01*
G01X726512Y1747992D02*
G02Y1740118I0J-3937D01*
G01X746198Y1747992D02*
G03Y1740118I0J-3937D01*
G01X766543Y35150D02*
Y38504D01*
G01Y35150D02*
Y38504D01*
G02X774417Y46378I7874J0D01*
G01X766543Y35150D02*
Y38504D01*
G02X774417Y46378I7874J0D01*
G01X871260D01*
G01X766543Y35150D02*
Y38504D01*
G02X774417Y46378I7874J0D01*
G01X871260D01*
G03X879134Y54252I0J7874D01*
G01X766543Y35150D02*
Y38504D01*
G02X774417Y46378I7874J0D01*
G01X871260D01*
G03X879134Y54252I0J7874D01*
G01Y114172D01*
G01X766543Y35150D02*
Y38504D01*
G02X774417Y46378I7874J0D01*
G01X871260D01*
G03X879134Y54252I0J7874D01*
G01Y114172D01*
G01X766543Y35150D02*
Y38504D01*
G02X774417Y46378I7874J0D01*
G01X871260D01*
G03X879134Y54252I0J7874D01*
G01Y114172D01*
G01X766543Y35150D02*
Y38504D01*
G02X774417Y46378I7874J0D01*
G01X871260D01*
G03X879134Y54252I0J7874D01*
G01Y114172D01*
G01X766543Y35150D02*
Y38504D01*
G02X774417Y46378I7874J0D01*
G01X871260D01*
G03X879134Y54252I0J7874D01*
G01Y114172D01*
G01X766543Y35150D02*
Y38504D01*
G02X774417Y46378I7874J0D01*
G01X871260D01*
G03X879134Y54252I0J7874D01*
G01Y114172D01*
G01X766543Y35150D02*
Y38504D01*
G02X774417Y46378I7874J0D01*
G01X871260D01*
G03X879134Y54252I0J7874D01*
G01Y114172D01*
G01X766543Y35150D02*
Y38504D01*
G02X774417Y46378I7874J0D01*
G01X871260D01*
G03X879134Y54252I0J7874D01*
G01Y114172D01*
G01X766543Y35150D02*
Y38504D01*
G02X774417Y46378I7874J0D01*
G01X871260D01*
G03X879134Y54252I0J7874D01*
G01Y114172D01*
G01X766543Y35150D02*
Y38504D01*
G02X774417Y46378I7874J0D01*
G01X871260D01*
G03X879134Y54252I0J7874D01*
G01Y114172D01*
G01X766543Y35150D02*
Y38504D01*
G02X774417Y46378I7874J0D01*
G01X871260D01*
G03X879134Y54252I0J7874D01*
G01Y114172D01*
G01X766543Y35150D02*
Y38504D01*
G02X774417Y46378I7874J0D01*
G01X871260D01*
G03X879134Y54252I0J7874D01*
G01Y114172D01*
G01X766543Y35150D02*
Y38504D01*
G02X774417Y46378I7874J0D01*
G01X871260D01*
G03X879134Y54252I0J7874D01*
G01Y114172D01*
G01X766543Y35150D02*
Y38504D01*
G02X774417Y46378I7874J0D01*
G01X871260D01*
G03X879134Y54252I0J7874D01*
G01Y114172D01*
G01X766543Y35150D02*
Y38504D01*
G02X774417Y46378I7874J0D01*
G01X871260D01*
G03X879134Y54252I0J7874D01*
G01Y114172D01*
G01X766543Y35150D02*
Y38504D01*
G02X774417Y46378I7874J0D01*
G01X871260D01*
G03X879134Y54252I0J7874D01*
G01Y114172D01*
G01X766543Y35150D02*
Y38504D01*
G02X774417Y46378I7874J0D01*
G01X871260D01*
G03X879134Y54252I0J7874D01*
G01Y114172D01*
G01X766543Y35150D02*
Y38504D01*
G02X774417Y46378I7874J0D01*
G01X871260D01*
G03X879134Y54252I0J7874D01*
G01Y114172D01*
G01X766543Y35150D02*
Y38504D01*
G02X774417Y46378I7874J0D01*
G01X871260D01*
G03X879134Y54252I0J7874D01*
G01Y114172D01*
G01X766543Y35150D02*
Y38504D01*
G02X774417Y46378I7874J0D01*
G01X871260D01*
G03X879134Y54252I0J7874D01*
G01Y114172D01*
G01X766543Y35150D02*
Y38504D01*
G02X774417Y46378I7874J0D01*
G01X871260D01*
G03X879134Y54252I0J7874D01*
G01Y114172D01*
G01X766543Y35150D02*
Y38504D01*
G02X774417Y46378I7874J0D01*
G01X871260D01*
G03X879134Y54252I0J7874D01*
G01Y114172D01*
G01X766543Y35150D02*
Y38504D01*
G02X774417Y46378I7874J0D01*
G01X871260D01*
G03X879134Y54252I0J7874D01*
G01Y114172D01*
G01X766543Y35150D02*
Y38504D01*
G02X774417Y46378I7874J0D01*
G01X871260D01*
G03X879134Y54252I0J7874D01*
G01Y114172D01*
G01X766543Y35150D02*
Y38504D01*
G02X774417Y46378I7874J0D01*
G01X871260D01*
G03X879134Y54252I0J7874D01*
G01Y114172D01*
G01X766543Y35150D02*
Y38504D01*
G02X774417Y46378I7874J0D01*
G01X871260D01*
G03X879134Y54252I0J7874D01*
G01Y114172D01*
G01X766543Y35150D02*
Y38504D01*
G02X774417Y46378I7874J0D01*
G01X871260D01*
G03X879134Y54252I0J7874D01*
G01Y114172D01*
G01X766543Y35150D02*
Y38504D01*
G02X774417Y46378I7874J0D01*
G01X871260D01*
G03X879134Y54252I0J7874D01*
G01Y114172D01*
G01X766543Y35150D02*
Y38504D01*
G02X774417Y46378I7874J0D01*
G01X871260D01*
G03X879134Y54252I0J7874D01*
G01Y114172D01*
G01X766543Y35150D02*
Y38504D01*
G02X774417Y46378I7874J0D01*
G01X871260D01*
G03X879134Y54252I0J7874D01*
G01Y114172D01*
G01X766543Y35150D02*
Y38504D01*
G02X774417Y46378I7874J0D01*
G01X871260D01*
G03X879134Y54252I0J7874D01*
G01Y114172D01*
G01X766543Y35150D02*
Y38504D01*
G02X774417Y46378I7874J0D01*
G01X871260D01*
G03X879134Y54252I0J7874D01*
G01Y114172D01*
G01X766543Y35150D02*
Y38504D01*
G02X774417Y46378I7874J0D01*
G01X871260D01*
G03X879134Y54252I0J7874D01*
G01Y114172D01*
G01X766543Y35150D02*
Y38504D01*
G02X774417Y46378I7874J0D01*
G01X871260D01*
G03X879134Y54252I0J7874D01*
G01Y114172D01*
G01X766543Y35150D02*
Y38504D01*
G02X774417Y46378I7874J0D01*
G01X871260D01*
G03X879134Y54252I0J7874D01*
G01Y114172D01*
G01X766543Y35150D02*
Y38504D01*
G02X774417Y46378I7874J0D01*
G01X871260D01*
G03X879134Y54252I0J7874D01*
G01Y114172D01*
G01X766543Y35150D02*
Y38504D01*
G02X774417Y46378I7874J0D01*
G01X871260D01*
G03X879134Y54252I0J7874D01*
G01Y114172D01*
G01X766543Y35150D02*
Y38504D01*
G02X774417Y46378I7874J0D01*
G01X871260D01*
G03X879134Y54252I0J7874D01*
G01Y114172D01*
G01X766543Y35150D02*
Y38504D01*
G02X774417Y46378I7874J0D01*
G01X871260D01*
G03X879134Y54252I0J7874D01*
G01Y114172D01*
G01X766543Y35150D02*
Y38504D01*
G02X774417Y46378I7874J0D01*
G01X871260D01*
G03X879134Y54252I0J7874D01*
G01Y114172D01*
G01X766543Y35150D02*
Y38504D01*
G02X774417Y46378I7874J0D01*
G01X871260D01*
G03X879134Y54252I0J7874D01*
G01Y114172D01*
G01X766543Y35150D02*
Y38504D01*
G02X774417Y46378I7874J0D01*
G01X871260D01*
G03X879134Y54252I0J7874D01*
G01Y114172D01*
G01X766543Y35150D02*
Y38504D01*
G02X774417Y46378I7874J0D01*
G01X871260D01*
G03X879134Y54252I0J7874D01*
G01Y114172D01*
G01X766543Y35150D02*
Y38504D01*
G01Y35150D02*
Y38504D01*
G02X774417Y46378I7874J0D01*
G01X766543Y35150D02*
Y38504D01*
G02X774417Y46378I7874J0D01*
G01X871260D01*
G01X766543Y35150D02*
Y38504D01*
G02X774417Y46378I7874J0D01*
G01X871260D01*
G03X879134Y54252I0J7874D01*
G01X766543Y35150D02*
Y38504D01*
G02X774417Y46378I7874J0D01*
G01X871260D01*
G03X879134Y54252I0J7874D01*
G01Y114172D01*
G01X766543Y35150D02*
Y38504D01*
G02X774417Y46378I7874J0D01*
G01X871260D01*
G03X879134Y54252I0J7874D01*
G01Y114172D01*
G01X766543Y35150D02*
Y38504D01*
G02X774417Y46378I7874J0D01*
G01X871260D01*
G03X879134Y54252I0J7874D01*
G01Y114172D01*
G01X766543Y35150D02*
Y38504D01*
G02X774417Y46378I7874J0D01*
G01X871260D01*
G03X879134Y54252I0J7874D01*
G01Y114172D01*
G01X766543Y35150D02*
Y38504D01*
G02X774417Y46378I7874J0D01*
G01X871260D01*
G03X879134Y54252I0J7874D01*
G01Y114172D01*
G01X766543Y35150D02*
Y38504D01*
G02X774417Y46378I7874J0D01*
G01X871260D01*
G03X879134Y54252I0J7874D01*
G01Y114172D01*
G01X766543Y35150D02*
Y38504D01*
G02X774417Y46378I7874J0D01*
G01X871260D01*
G03X879134Y54252I0J7874D01*
G01Y114172D01*
G01X766543Y35150D02*
Y38504D01*
G02X774417Y46378I7874J0D01*
G01X871260D01*
G03X879134Y54252I0J7874D01*
G01Y114172D01*
G01X766543Y35150D02*
Y38504D01*
G02X774417Y46378I7874J0D01*
G01X871260D01*
G03X879134Y54252I0J7874D01*
G01Y114172D01*
G01X766543Y35150D02*
Y38504D01*
G02X774417Y46378I7874J0D01*
G01X871260D01*
G03X879134Y54252I0J7874D01*
G01Y114172D01*
G01X766543Y35150D02*
Y38504D01*
G02X774417Y46378I7874J0D01*
G01X871260D01*
G03X879134Y54252I0J7874D01*
G01Y114172D01*
G01X766543Y35150D02*
Y38504D01*
G02X774417Y46378I7874J0D01*
G01X871260D01*
G03X879134Y54252I0J7874D01*
G01Y114172D01*
G01X766543Y35150D02*
Y38504D01*
G02X774417Y46378I7874J0D01*
G01X871260D01*
G03X879134Y54252I0J7874D01*
G01Y114172D01*
G01X766543Y35150D02*
Y38504D01*
G02X774417Y46378I7874J0D01*
G01X871260D01*
G03X879134Y54252I0J7874D01*
G01Y114172D01*
G01X766543Y35150D02*
Y38504D01*
G02X774417Y46378I7874J0D01*
G01X871260D01*
G03X879134Y54252I0J7874D01*
G01Y114172D01*
G01X766543Y35150D02*
Y38504D01*
G02X774417Y46378I7874J0D01*
G01X871260D01*
G03X879134Y54252I0J7874D01*
G01Y114172D01*
G01X766543Y35150D02*
Y38504D01*
G02X774417Y46378I7874J0D01*
G01X871260D01*
G03X879134Y54252I0J7874D01*
G01Y114172D01*
G01X766543Y35150D02*
Y38504D01*
G02X774417Y46378I7874J0D01*
G01X871260D01*
G03X879134Y54252I0J7874D01*
G01Y114172D01*
G01X766543Y35150D02*
Y38504D01*
G02X774417Y46378I7874J0D01*
G01X871260D01*
G03X879134Y54252I0J7874D01*
G01Y114172D01*
G01X766543Y35150D02*
Y38504D01*
G02X774417Y46378I7874J0D01*
G01X871260D01*
G03X879134Y54252I0J7874D01*
G01Y114172D01*
G01X766543Y35150D02*
Y38504D01*
G02X774417Y46378I7874J0D01*
G01X871260D01*
G03X879134Y54252I0J7874D01*
G01Y114172D01*
G01X766543Y35150D02*
Y38504D01*
G02X774417Y46378I7874J0D01*
G01X871260D01*
G03X879134Y54252I0J7874D01*
G01Y114172D01*
G01X766543Y35150D02*
Y38504D01*
G02X774417Y46378I7874J0D01*
G01X871260D01*
G03X879134Y54252I0J7874D01*
G01Y114172D01*
G01X766543Y35150D02*
Y38504D01*
G02X774417Y46378I7874J0D01*
G01X871260D01*
G03X879134Y54252I0J7874D01*
G01Y114172D01*
G01X766543Y35150D02*
Y38504D01*
G02X774417Y46378I7874J0D01*
G01X871260D01*
G03X879134Y54252I0J7874D01*
G01Y114172D01*
G01X766543Y35150D02*
Y38504D01*
G02X774417Y46378I7874J0D01*
G01X871260D01*
G03X879134Y54252I0J7874D01*
G01Y114172D01*
G01X766543Y35150D02*
Y38504D01*
G02X774417Y46378I7874J0D01*
G01X871260D01*
G03X879134Y54252I0J7874D01*
G01Y114172D01*
G01X766543Y35150D02*
Y38504D01*
G02X774417Y46378I7874J0D01*
G01X871260D01*
G03X879134Y54252I0J7874D01*
G01Y114172D01*
G01X766543Y35150D02*
Y38504D01*
G02X774417Y46378I7874J0D01*
G01X871260D01*
G03X879134Y54252I0J7874D01*
G01Y114172D01*
G01X766543Y35150D02*
Y38504D01*
G02X774417Y46378I7874J0D01*
G01X871260D01*
G03X879134Y54252I0J7874D01*
G01Y114172D01*
G01X766543Y35150D02*
Y38504D01*
G02X774417Y46378I7874J0D01*
G01X871260D01*
G03X879134Y54252I0J7874D01*
G01Y114172D01*
G01X766543Y35150D02*
Y38504D01*
G02X774417Y46378I7874J0D01*
G01X871260D01*
G03X879134Y54252I0J7874D01*
G01Y114172D01*
G01X766543Y35150D02*
Y38504D01*
G02X774417Y46378I7874J0D01*
G01X871260D01*
G03X879134Y54252I0J7874D01*
G01Y114172D01*
G01X766543Y35150D02*
Y38504D01*
G02X774417Y46378I7874J0D01*
G01X871260D01*
G03X879134Y54252I0J7874D01*
G01Y114172D01*
G01X766543Y35150D02*
Y38504D01*
G02X774417Y46378I7874J0D01*
G01X871260D01*
G03X879134Y54252I0J7874D01*
G01Y114172D01*
G01X766543Y35150D02*
Y38504D01*
G02X774417Y46378I7874J0D01*
G01X871260D01*
G03X879134Y54252I0J7874D01*
G01Y114172D01*
G01X766543Y35150D02*
Y38504D01*
G02X774417Y46378I7874J0D01*
G01X871260D01*
G03X879134Y54252I0J7874D01*
G01Y114172D01*
G01X766543Y35150D02*
Y38504D01*
G02X774417Y46378I7874J0D01*
G01X871260D01*
G03X879134Y54252I0J7874D01*
G01Y114172D01*
G01X766543Y35150D02*
Y38504D01*
G02X774417Y46378I7874J0D01*
G01X871260D01*
G03X879134Y54252I0J7874D01*
G01Y114172D01*
G01X766543Y35150D02*
Y38504D01*
G02X774417Y46378I7874J0D01*
G01X871260D01*
G03X879134Y54252I0J7874D01*
G01Y114172D01*
G01X766543Y35150D02*
Y38504D01*
G02X774417Y46378I7874J0D01*
G01X871260D01*
G03X879134Y54252I0J7874D01*
G01Y114172D01*
G01X766543Y35150D02*
Y38504D01*
G02X774417Y46378I7874J0D01*
G01X871260D01*
G03X879134Y54252I0J7874D01*
G01Y114172D01*
G01X1796071Y16549D02*
Y38504D01*
G02X1803945Y46378I7874J0D01*
G01X1849606D01*
G03X1857480Y54252I0J7874D01*
G01Y305793D01*
G03X1855174Y311361I-7874J0D01*
G01X1846007Y320528D01*
G02X1843701Y326096I5568J5568D01*
G01Y1593982D01*
G03X1841395Y1599550I-7874J0D01*
G01X1834196Y1606749D01*
G02X1831890Y1612316I5567J5567D01*
G01Y1732244D01*
G03X1824016Y1740118I-7874J0D01*
G01X1091791D01*
G03X1089823Y1738149I0J-1968D01*
G01Y1736890D01*
G02X1087854Y1734921I-1969J0D01*
G01X769705D01*
G02X767736Y1736890I0J1969D01*
G01Y1738149D01*
G03X765768Y1740118I-1968J0D01*
G01X1796071Y16549D02*
Y38504D01*
G02X1803945Y46378I7874J0D01*
G01X1849606D01*
G03X1857480Y54252I0J7874D01*
G01Y305793D01*
G03X1855174Y311361I-7874J0D01*
G01X1846007Y320528D01*
G02X1843701Y326096I5568J5568D01*
G01Y1593982D01*
G03X1841395Y1599550I-7874J0D01*
G01X1834196Y1606749D01*
G02X1831890Y1612316I5567J5567D01*
G01Y1732244D01*
G03X1824016Y1740118I-7874J0D01*
G01X1091791D01*
G03X1089823Y1738149I0J-1968D01*
G01Y1736890D01*
G02X1087854Y1734921I-1969J0D01*
G01X769705D01*
G02X767736Y1736890I0J1969D01*
G01Y1738149D01*
G03X765768Y1740118I-1968J0D01*
G01X1796071Y16549D02*
Y38504D01*
G02X1803945Y46378I7874J0D01*
G01X1849606D01*
G03X1857480Y54252I0J7874D01*
G01Y305793D01*
G03X1855174Y311361I-7874J0D01*
G01X1846007Y320528D01*
G02X1843701Y326096I5568J5568D01*
G01Y1593982D01*
G03X1841395Y1599550I-7874J0D01*
G01X1834196Y1606749D01*
G02X1831890Y1612316I5567J5567D01*
G01Y1732244D01*
G03X1824016Y1740118I-7874J0D01*
G01X1091791D01*
G03X1089823Y1738149I0J-1968D01*
G01Y1736890D01*
G02X1087854Y1734921I-1969J0D01*
G01X769705D01*
G01X1796071Y16549D02*
Y38504D01*
G02X1803945Y46378I7874J0D01*
G01X1849606D01*
G03X1857480Y54252I0J7874D01*
G01Y305793D01*
G03X1855174Y311361I-7874J0D01*
G01X1846007Y320528D01*
G02X1843701Y326096I5568J5568D01*
G01Y1593982D01*
G03X1841395Y1599550I-7874J0D01*
G01X1834196Y1606749D01*
G02X1831890Y1612316I5567J5567D01*
G01Y1732244D01*
G03X1824016Y1740118I-7874J0D01*
G01X1091791D01*
G03X1089823Y1738149I0J-1968D01*
G01Y1736890D01*
G02X1087854Y1734921I-1969J0D01*
G01X769705D01*
G02X767736Y1736890I0J1969D01*
G01X1796071Y16549D02*
Y38504D01*
G02X1803945Y46378I7874J0D01*
G01X1849606D01*
G03X1857480Y54252I0J7874D01*
G01Y305793D01*
G03X1855174Y311361I-7874J0D01*
G01X1846007Y320528D01*
G02X1843701Y326096I5568J5568D01*
G01Y1593982D01*
G03X1841395Y1599550I-7874J0D01*
G01X1834196Y1606749D01*
G02X1831890Y1612316I5567J5567D01*
G01Y1732244D01*
G03X1824016Y1740118I-7874J0D01*
G01X1091791D01*
G03X1089823Y1738149I0J-1968D01*
G01Y1736890D01*
G02X1087854Y1734921I-1969J0D01*
G01X769705D01*
G02X767736Y1736890I0J1969D01*
G01Y1738149D01*
G01X1796071Y16549D02*
Y38504D01*
G02X1803945Y46378I7874J0D01*
G01X1849606D01*
G03X1857480Y54252I0J7874D01*
G01Y305793D01*
G03X1855174Y311361I-7874J0D01*
G01X1846007Y320528D01*
G02X1843701Y326096I5568J5568D01*
G01Y1593982D01*
G03X1841395Y1599550I-7874J0D01*
G01X1834196Y1606749D01*
G02X1831890Y1612316I5567J5567D01*
G01Y1732244D01*
G03X1824016Y1740118I-7874J0D01*
G01X1091791D01*
G03X1089823Y1738149I0J-1968D01*
G01Y1736890D01*
G02X1087854Y1734921I-1969J0D01*
G01X769705D01*
G01X1796071Y16549D02*
Y38504D01*
G02X1803945Y46378I7874J0D01*
G01X1849606D01*
G03X1857480Y54252I0J7874D01*
G01Y305793D01*
G03X1855174Y311361I-7874J0D01*
G01X1846007Y320528D01*
G02X1843701Y326096I5568J5568D01*
G01Y1593982D01*
G03X1841395Y1599550I-7874J0D01*
G01X1834196Y1606749D01*
G02X1831890Y1612316I5567J5567D01*
G01Y1732244D01*
G03X1824016Y1740118I-7874J0D01*
G01X1091791D01*
G03X1089823Y1738149I0J-1968D01*
G01Y1736890D01*
G02X1087854Y1734921I-1969J0D01*
G01X769705D01*
G02X767736Y1736890I0J1969D01*
G01X1796071Y16549D02*
Y38504D01*
G02X1803945Y46378I7874J0D01*
G01X1849606D01*
G03X1857480Y54252I0J7874D01*
G01Y305793D01*
G03X1855174Y311361I-7874J0D01*
G01X1846007Y320528D01*
G02X1843701Y326096I5568J5568D01*
G01Y1593982D01*
G03X1841395Y1599550I-7874J0D01*
G01X1834196Y1606749D01*
G02X1831890Y1612316I5567J5567D01*
G01Y1732244D01*
G03X1824016Y1740118I-7874J0D01*
G01X1091791D01*
G03X1089823Y1738149I0J-1968D01*
G01Y1736890D01*
G02X1087854Y1734921I-1969J0D01*
G01X769705D01*
G02X767736Y1736890I0J1969D01*
G01Y1738149D01*
G01X788190Y46378D02*
G02Y38504I0J-3937D01*
G01X807876Y46378D02*
G03Y38504I0J-3937D01*
G01X887008Y70894D02*
G03X879134I-3937J0D01*
G01X887008Y90580D02*
G02X879134I-3937J0D01*
G01Y119303D02*
Y134331D01*
G02X887008Y142205I7874J0D01*
G01X879134Y119303D02*
Y134331D01*
G02X887008Y142205I7874J0D01*
G01X1011024D01*
G01X879134Y119303D02*
Y134331D01*
G02X887008Y142205I7874J0D01*
G01X1011024D01*
G02X1018898Y134331I0J-7874D01*
G01X879134Y119303D02*
Y134331D01*
G02X887008Y142205I7874J0D01*
G01X1011024D01*
G02X1018898Y134331I0J-7874D01*
G01Y119303D01*
G01X879134D02*
Y134331D01*
G02X887008Y142205I7874J0D01*
G01X1011024D01*
G02X1018898Y134331I0J-7874D01*
G01Y119303D01*
G01X879134D02*
Y134331D01*
G02X887008Y142205I7874J0D01*
G01X1011024D01*
G02X1018898Y134331I0J-7874D01*
G01Y119303D01*
G01X879134D02*
Y134331D01*
G02X887008Y142205I7874J0D01*
G01X1011024D01*
G02X1018898Y134331I0J-7874D01*
G01Y119303D01*
G01X879134D02*
Y134331D01*
G02X887008Y142205I7874J0D01*
G01X1011024D01*
G02X1018898Y134331I0J-7874D01*
G01Y119303D01*
G01X879134D02*
Y134331D01*
G02X887008Y142205I7874J0D01*
G01X1011024D01*
G02X1018898Y134331I0J-7874D01*
G01Y119303D01*
G01X879134D02*
Y134331D01*
G02X887008Y142205I7874J0D01*
G01X1011024D01*
G02X1018898Y134331I0J-7874D01*
G01Y119303D01*
G01X879134D02*
Y134331D01*
G02X887008Y142205I7874J0D01*
G01X1011024D01*
G02X1018898Y134331I0J-7874D01*
G01Y119303D01*
G01X879134D02*
Y134331D01*
G02X887008Y142205I7874J0D01*
G01X1011024D01*
G02X1018898Y134331I0J-7874D01*
G01Y119303D01*
G01X879134D02*
Y134331D01*
G02X887008Y142205I7874J0D01*
G01X1011024D01*
G02X1018898Y134331I0J-7874D01*
G01Y119303D01*
G01X879134D02*
Y134331D01*
G02X887008Y142205I7874J0D01*
G01X1011024D01*
G02X1018898Y134331I0J-7874D01*
G01Y119303D01*
G01X879134D02*
Y134331D01*
G02X887008Y142205I7874J0D01*
G01X1011024D01*
G02X1018898Y134331I0J-7874D01*
G01Y119303D01*
G01X879134D02*
Y134331D01*
G02X887008Y142205I7874J0D01*
G01X1011024D01*
G02X1018898Y134331I0J-7874D01*
G01Y119303D01*
G01X879134D02*
Y134331D01*
G02X887008Y142205I7874J0D01*
G01X1011024D01*
G02X1018898Y134331I0J-7874D01*
G01Y119303D01*
G01X879134D02*
Y134331D01*
G02X887008Y142205I7874J0D01*
G01X1011024D01*
G02X1018898Y134331I0J-7874D01*
G01Y119303D01*
G01X879134D02*
Y134331D01*
G02X887008Y142205I7874J0D01*
G01X1011024D01*
G02X1018898Y134331I0J-7874D01*
G01Y119303D01*
G01X879134D02*
Y134331D01*
G02X887008Y142205I7874J0D01*
G01X1011024D01*
G02X1018898Y134331I0J-7874D01*
G01Y119303D01*
G01X879134D02*
Y134331D01*
G02X887008Y142205I7874J0D01*
G01X1011024D01*
G02X1018898Y134331I0J-7874D01*
G01Y119303D01*
G01X879134D02*
Y134331D01*
G02X887008Y142205I7874J0D01*
G01X1011024D01*
G02X1018898Y134331I0J-7874D01*
G01Y119303D01*
G01X879134D02*
Y134331D01*
G02X887008Y142205I7874J0D01*
G01X1011024D01*
G02X1018898Y134331I0J-7874D01*
G01Y119303D01*
G01X879134D02*
Y134331D01*
G02X887008Y142205I7874J0D01*
G01X1011024D01*
G02X1018898Y134331I0J-7874D01*
G01Y119303D01*
G01X879134D02*
Y134331D01*
G02X887008Y142205I7874J0D01*
G01X1011024D01*
G02X1018898Y134331I0J-7874D01*
G01Y119303D01*
G01X879134D02*
Y134331D01*
G02X887008Y142205I7874J0D01*
G01X1011024D01*
G02X1018898Y134331I0J-7874D01*
G01Y119303D01*
G01X879134D02*
Y134331D01*
G02X887008Y142205I7874J0D01*
G01X1011024D01*
G02X1018898Y134331I0J-7874D01*
G01Y119303D01*
G01X879134D02*
Y134331D01*
G02X887008Y142205I7874J0D01*
G01X1011024D01*
G02X1018898Y134331I0J-7874D01*
G01Y119303D01*
G01X879134D02*
Y134331D01*
G02X887008Y142205I7874J0D01*
G01X1011024D01*
G02X1018898Y134331I0J-7874D01*
G01Y119303D01*
G01X879134D02*
Y134331D01*
G02X887008Y142205I7874J0D01*
G01X1011024D01*
G02X1018898Y134331I0J-7874D01*
G01Y119303D01*
G01X879134D02*
Y134331D01*
G02X887008Y142205I7874J0D01*
G01X1011024D01*
G02X1018898Y134331I0J-7874D01*
G01Y119303D01*
G01X879134D02*
Y134331D01*
G02X887008Y142205I7874J0D01*
G01X1011024D01*
G02X1018898Y134331I0J-7874D01*
G01Y119303D01*
G01X879134D02*
Y134331D01*
G02X887008Y142205I7874J0D01*
G01X1011024D01*
G02X1018898Y134331I0J-7874D01*
G01Y119303D01*
G01X879134D02*
Y134331D01*
G02X887008Y142205I7874J0D01*
G01X1011024D01*
G02X1018898Y134331I0J-7874D01*
G01Y119303D01*
G01X879134D02*
Y134331D01*
G02X887008Y142205I7874J0D01*
G01X1011024D01*
G02X1018898Y134331I0J-7874D01*
G01Y119303D01*
G01X879134D02*
Y134331D01*
G02X887008Y142205I7874J0D01*
G01X1011024D01*
G02X1018898Y134331I0J-7874D01*
G01Y119303D01*
G01X879134D02*
Y134331D01*
G02X887008Y142205I7874J0D01*
G01X1011024D01*
G02X1018898Y134331I0J-7874D01*
G01Y119303D01*
G01X879134D02*
Y134331D01*
G02X887008Y142205I7874J0D01*
G01X1011024D01*
G02X1018898Y134331I0J-7874D01*
G01Y119303D01*
G01X879134D02*
Y134331D01*
G02X887008Y142205I7874J0D01*
G01X1011024D01*
G02X1018898Y134331I0J-7874D01*
G01Y119303D01*
G01X879134D02*
Y134331D01*
G02X887008Y142205I7874J0D01*
G01X1011024D01*
G02X1018898Y134331I0J-7874D01*
G01Y119303D01*
G01X879134D02*
Y134331D01*
G02X887008Y142205I7874J0D01*
G01X1011024D01*
G02X1018898Y134331I0J-7874D01*
G01Y119303D01*
G01X879134D02*
Y134331D01*
G01Y119303D02*
Y134331D01*
G02X887008Y142205I7874J0D01*
G01X879134Y119303D02*
Y134331D01*
G02X887008Y142205I7874J0D01*
G01X1011024D01*
G01X879134Y119303D02*
Y134331D01*
G02X887008Y142205I7874J0D01*
G01X1011024D01*
G02X1018898Y134331I0J-7874D01*
G01X879134Y119303D02*
Y134331D01*
G02X887008Y142205I7874J0D01*
G01X1011024D01*
G02X1018898Y134331I0J-7874D01*
G01Y119303D01*
G01X879134D02*
Y134331D01*
G02X887008Y142205I7874J0D01*
G01X1011024D01*
G02X1018898Y134331I0J-7874D01*
G01Y119303D01*
G01X879134D02*
Y134331D01*
G02X887008Y142205I7874J0D01*
G01X1011024D01*
G02X1018898Y134331I0J-7874D01*
G01Y119303D01*
G01X879134D02*
Y134331D01*
G02X887008Y142205I7874J0D01*
G01X1011024D01*
G02X1018898Y134331I0J-7874D01*
G01Y119303D01*
G01X879134D02*
Y134331D01*
G02X887008Y142205I7874J0D01*
G01X1011024D01*
G02X1018898Y134331I0J-7874D01*
G01Y119303D01*
G01X879134D02*
Y134331D01*
G02X887008Y142205I7874J0D01*
G01X1011024D01*
G02X1018898Y134331I0J-7874D01*
G01Y119303D01*
G01X879134D02*
Y134331D01*
G02X887008Y142205I7874J0D01*
G01X1011024D01*
G02X1018898Y134331I0J-7874D01*
G01Y119303D01*
G01X879134D02*
Y134331D01*
G02X887008Y142205I7874J0D01*
G01X1011024D01*
G02X1018898Y134331I0J-7874D01*
G01Y119303D01*
G01X879134D02*
Y134331D01*
G02X887008Y142205I7874J0D01*
G01X1011024D01*
G02X1018898Y134331I0J-7874D01*
G01Y119303D01*
G01X879134D02*
Y134331D01*
G02X887008Y142205I7874J0D01*
G01X1011024D01*
G02X1018898Y134331I0J-7874D01*
G01Y119303D01*
G01X879134D02*
Y134331D01*
G02X887008Y142205I7874J0D01*
G01X1011024D01*
G02X1018898Y134331I0J-7874D01*
G01Y119303D01*
G01X879134D02*
Y134331D01*
G02X887008Y142205I7874J0D01*
G01X1011024D01*
G02X1018898Y134331I0J-7874D01*
G01Y119303D01*
G01X879134D02*
Y134331D01*
G02X887008Y142205I7874J0D01*
G01X1011024D01*
G02X1018898Y134331I0J-7874D01*
G01Y119303D01*
G01X879134D02*
Y134331D01*
G02X887008Y142205I7874J0D01*
G01X1011024D01*
G02X1018898Y134331I0J-7874D01*
G01Y119303D01*
G01X879134D02*
Y134331D01*
G02X887008Y142205I7874J0D01*
G01X1011024D01*
G02X1018898Y134331I0J-7874D01*
G01Y119303D01*
G01X879134D02*
Y134331D01*
G02X887008Y142205I7874J0D01*
G01X1011024D01*
G02X1018898Y134331I0J-7874D01*
G01Y119303D01*
G01X879134D02*
Y134331D01*
G02X887008Y142205I7874J0D01*
G01X1011024D01*
G02X1018898Y134331I0J-7874D01*
G01Y119303D01*
G01X879134D02*
Y134331D01*
G02X887008Y142205I7874J0D01*
G01X1011024D01*
G02X1018898Y134331I0J-7874D01*
G01Y119303D01*
G01X879134D02*
Y134331D01*
G02X887008Y142205I7874J0D01*
G01X1011024D01*
G02X1018898Y134331I0J-7874D01*
G01Y119303D01*
G01X879134D02*
Y134331D01*
G02X887008Y142205I7874J0D01*
G01X1011024D01*
G02X1018898Y134331I0J-7874D01*
G01Y119303D01*
G01X879134D02*
Y134331D01*
G02X887008Y142205I7874J0D01*
G01X1011024D01*
G02X1018898Y134331I0J-7874D01*
G01Y119303D01*
G01X879134D02*
Y134331D01*
G02X887008Y142205I7874J0D01*
G01X1011024D01*
G02X1018898Y134331I0J-7874D01*
G01Y119303D01*
G01X879134D02*
Y134331D01*
G02X887008Y142205I7874J0D01*
G01X1011024D01*
G02X1018898Y134331I0J-7874D01*
G01Y119303D01*
G01X879134D02*
Y134331D01*
G02X887008Y142205I7874J0D01*
G01X1011024D01*
G02X1018898Y134331I0J-7874D01*
G01Y119303D01*
G01X879134D02*
Y134331D01*
G02X887008Y142205I7874J0D01*
G01X1011024D01*
G02X1018898Y134331I0J-7874D01*
G01Y119303D01*
G01X879134D02*
Y134331D01*
G02X887008Y142205I7874J0D01*
G01X1011024D01*
G02X1018898Y134331I0J-7874D01*
G01Y119303D01*
G01X879134D02*
Y134331D01*
G02X887008Y142205I7874J0D01*
G01X1011024D01*
G02X1018898Y134331I0J-7874D01*
G01Y119303D01*
G01X879134D02*
Y134331D01*
G02X887008Y142205I7874J0D01*
G01X1011024D01*
G02X1018898Y134331I0J-7874D01*
G01Y119303D01*
G01X879134D02*
Y134331D01*
G02X887008Y142205I7874J0D01*
G01X1011024D01*
G02X1018898Y134331I0J-7874D01*
G01Y119303D01*
G01X879134D02*
Y134331D01*
G02X887008Y142205I7874J0D01*
G01X1011024D01*
G02X1018898Y134331I0J-7874D01*
G01Y119303D01*
G01X879134D02*
Y134331D01*
G02X887008Y142205I7874J0D01*
G01X1011024D01*
G02X1018898Y134331I0J-7874D01*
G01Y119303D01*
G01X879134D02*
Y134331D01*
G02X887008Y142205I7874J0D01*
G01X1011024D01*
G02X1018898Y134331I0J-7874D01*
G01Y119303D01*
G01X879134D02*
Y134331D01*
G02X887008Y142205I7874J0D01*
G01X1011024D01*
G02X1018898Y134331I0J-7874D01*
G01Y119303D01*
G01X879134D02*
Y134331D01*
G02X887008Y142205I7874J0D01*
G01X1011024D01*
G02X1018898Y134331I0J-7874D01*
G01Y119303D01*
G01X879134D02*
Y134331D01*
G02X887008Y142205I7874J0D01*
G01X1011024D01*
G02X1018898Y134331I0J-7874D01*
G01Y119303D01*
G01X879134D02*
Y134331D01*
G02X887008Y142205I7874J0D01*
G01X1011024D01*
G02X1018898Y134331I0J-7874D01*
G01Y119303D01*
G01X879134D02*
Y134331D01*
G02X887008Y142205I7874J0D01*
G01X1011024D01*
G02X1018898Y134331I0J-7874D01*
G01Y119303D01*
G01X879134D02*
Y134331D01*
G02X887008Y142205I7874J0D01*
G01X1011024D01*
G02X1018898Y134331I0J-7874D01*
G01Y119303D01*
G01X879134D02*
Y134331D01*
G02X887008Y142205I7874J0D01*
G01X1011024D01*
G02X1018898Y134331I0J-7874D01*
G01Y119303D01*
G01X1525992Y1969D02*
Y38504D01*
G03X1518118Y46378I-7874J0D01*
G01X1026772D01*
G02X1018898Y54252I0J7874D01*
G01Y134331D01*
G03X1011024Y142205I-7874J0D01*
G01X887008D01*
G03X879134Y134331I0J-7874D01*
G01Y119303D01*
G01X887008Y46378D02*
Y130394D01*
G01D02*
G02X890945Y134331I3937J0D01*
G01X1007087D02*
X890945D01*
G01X909688D02*
G03Y142205I0J3937D01*
G01X929374Y134331D02*
G02Y142205I0J3937D01*
G01X1857480Y-40945D02*
Y30630D01*
G03X1849606Y38504I-7874J0D01*
G01X1811819D01*
G03X1803945Y30630I0J-7874D01*
G01Y-1575D01*
G02X1796071Y-9449I-7874J0D01*
G01X1525992D01*
G02X1518118Y-1575I0J7874D01*
G01Y30630D01*
G03X1510244Y38504I-7874J0D01*
G01X1018898D01*
G02X1011024Y46378I0J7874D01*
G01D02*
Y130394D01*
G01X1018898Y114172D02*
Y54252D01*
G01Y114172D02*
Y54252D01*
G03X1026772Y46378I7874J0D01*
G01X1018898Y114172D02*
Y54252D01*
G03X1026772Y46378I7874J0D01*
G01X1518118D01*
G01X1018898Y114172D02*
Y54252D01*
G03X1026772Y46378I7874J0D01*
G01X1518118D01*
G02X1525992Y38504I0J-7874D01*
G01X1018898Y114172D02*
Y54252D01*
G03X1026772Y46378I7874J0D01*
G01X1518118D01*
G02X1525992Y38504I0J-7874D01*
G01Y16549D01*
G01X1018898Y114172D02*
Y54252D01*
G03X1026772Y46378I7874J0D01*
G01X1518118D01*
G02X1525992Y38504I0J-7874D01*
G01Y16549D01*
G01X1018898Y114172D02*
Y54252D01*
G03X1026772Y46378I7874J0D01*
G01X1518118D01*
G02X1525992Y38504I0J-7874D01*
G01Y16549D01*
G01X1018898Y114172D02*
Y54252D01*
G03X1026772Y46378I7874J0D01*
G01X1518118D01*
G02X1525992Y38504I0J-7874D01*
G01Y16549D01*
G01X1018898Y114172D02*
Y54252D01*
G03X1026772Y46378I7874J0D01*
G01X1518118D01*
G02X1525992Y38504I0J-7874D01*
G01Y16549D01*
G01X1018898Y114172D02*
Y54252D01*
G03X1026772Y46378I7874J0D01*
G01X1518118D01*
G02X1525992Y38504I0J-7874D01*
G01Y16549D01*
G01X1018898Y114172D02*
Y54252D01*
G03X1026772Y46378I7874J0D01*
G01X1518118D01*
G02X1525992Y38504I0J-7874D01*
G01Y16549D01*
G01X1018898Y114172D02*
Y54252D01*
G03X1026772Y46378I7874J0D01*
G01X1518118D01*
G02X1525992Y38504I0J-7874D01*
G01Y16549D01*
G01X1018898Y114172D02*
Y54252D01*
G03X1026772Y46378I7874J0D01*
G01X1518118D01*
G02X1525992Y38504I0J-7874D01*
G01Y16549D01*
G01X1018898Y114172D02*
Y54252D01*
G03X1026772Y46378I7874J0D01*
G01X1518118D01*
G02X1525992Y38504I0J-7874D01*
G01Y16549D01*
G01X1018898Y114172D02*
Y54252D01*
G03X1026772Y46378I7874J0D01*
G01X1518118D01*
G02X1525992Y38504I0J-7874D01*
G01Y16549D01*
G01X1018898Y114172D02*
Y54252D01*
G03X1026772Y46378I7874J0D01*
G01X1518118D01*
G02X1525992Y38504I0J-7874D01*
G01Y16549D01*
G01X1018898Y114172D02*
Y54252D01*
G03X1026772Y46378I7874J0D01*
G01X1518118D01*
G02X1525992Y38504I0J-7874D01*
G01Y16549D01*
G01X1018898Y114172D02*
Y54252D01*
G03X1026772Y46378I7874J0D01*
G01X1518118D01*
G02X1525992Y38504I0J-7874D01*
G01Y16549D01*
G01X1018898Y114172D02*
Y54252D01*
G03X1026772Y46378I7874J0D01*
G01X1518118D01*
G02X1525992Y38504I0J-7874D01*
G01Y16549D01*
G01X1018898Y114172D02*
Y54252D01*
G03X1026772Y46378I7874J0D01*
G01X1518118D01*
G02X1525992Y38504I0J-7874D01*
G01Y16549D01*
G01X1018898Y114172D02*
Y54252D01*
G03X1026772Y46378I7874J0D01*
G01X1518118D01*
G02X1525992Y38504I0J-7874D01*
G01Y16549D01*
G01X1018898Y114172D02*
Y54252D01*
G03X1026772Y46378I7874J0D01*
G01X1518118D01*
G02X1525992Y38504I0J-7874D01*
G01Y16549D01*
G01X1018898Y114172D02*
Y54252D01*
G03X1026772Y46378I7874J0D01*
G01X1518118D01*
G02X1525992Y38504I0J-7874D01*
G01Y16549D01*
G01X1018898Y114172D02*
Y54252D01*
G03X1026772Y46378I7874J0D01*
G01X1518118D01*
G02X1525992Y38504I0J-7874D01*
G01Y16549D01*
G01X1018898Y114172D02*
Y54252D01*
G03X1026772Y46378I7874J0D01*
G01X1518118D01*
G02X1525992Y38504I0J-7874D01*
G01Y16549D01*
G01X1018898Y114172D02*
Y54252D01*
G03X1026772Y46378I7874J0D01*
G01X1518118D01*
G02X1525992Y38504I0J-7874D01*
G01Y16549D01*
G01X1018898Y114172D02*
Y54252D01*
G03X1026772Y46378I7874J0D01*
G01X1518118D01*
G02X1525992Y38504I0J-7874D01*
G01Y16549D01*
G01X1018898Y114172D02*
Y54252D01*
G03X1026772Y46378I7874J0D01*
G01X1518118D01*
G02X1525992Y38504I0J-7874D01*
G01Y16549D01*
G01X1018898Y114172D02*
Y54252D01*
G03X1026772Y46378I7874J0D01*
G01X1518118D01*
G02X1525992Y38504I0J-7874D01*
G01Y16549D01*
G01X1018898Y114172D02*
Y54252D01*
G03X1026772Y46378I7874J0D01*
G01X1518118D01*
G02X1525992Y38504I0J-7874D01*
G01Y16549D01*
G01X1018898Y114172D02*
Y54252D01*
G03X1026772Y46378I7874J0D01*
G01X1518118D01*
G02X1525992Y38504I0J-7874D01*
G01Y16549D01*
G01X1018898Y114172D02*
Y54252D01*
G03X1026772Y46378I7874J0D01*
G01X1518118D01*
G02X1525992Y38504I0J-7874D01*
G01Y16549D01*
G01X1018898Y114172D02*
Y54252D01*
G03X1026772Y46378I7874J0D01*
G01X1518118D01*
G02X1525992Y38504I0J-7874D01*
G01Y16549D01*
G01X1018898Y114172D02*
Y54252D01*
G03X1026772Y46378I7874J0D01*
G01X1518118D01*
G02X1525992Y38504I0J-7874D01*
G01Y16549D01*
G01X1018898Y114172D02*
Y54252D01*
G03X1026772Y46378I7874J0D01*
G01X1518118D01*
G02X1525992Y38504I0J-7874D01*
G01Y16549D01*
G01X1018898Y114172D02*
Y54252D01*
G03X1026772Y46378I7874J0D01*
G01X1518118D01*
G02X1525992Y38504I0J-7874D01*
G01Y16549D01*
G01X1018898Y114172D02*
Y54252D01*
G03X1026772Y46378I7874J0D01*
G01X1518118D01*
G02X1525992Y38504I0J-7874D01*
G01Y16549D01*
G01X1018898Y114172D02*
Y54252D01*
G03X1026772Y46378I7874J0D01*
G01X1518118D01*
G02X1525992Y38504I0J-7874D01*
G01Y16549D01*
G01X1018898Y114172D02*
Y54252D01*
G03X1026772Y46378I7874J0D01*
G01X1518118D01*
G02X1525992Y38504I0J-7874D01*
G01Y16549D01*
G01X1018898Y114172D02*
Y54252D01*
G01Y114172D02*
Y54252D01*
G03X1026772Y46378I7874J0D01*
G01X1018898Y114172D02*
Y54252D01*
G03X1026772Y46378I7874J0D01*
G01X1518118D01*
G01X1018898Y114172D02*
Y54252D01*
G03X1026772Y46378I7874J0D01*
G01X1518118D01*
G02X1525992Y38504I0J-7874D01*
G01X1018898Y114172D02*
Y54252D01*
G03X1026772Y46378I7874J0D01*
G01X1518118D01*
G02X1525992Y38504I0J-7874D01*
G01Y16549D01*
G01X1018898Y114172D02*
Y54252D01*
G03X1026772Y46378I7874J0D01*
G01X1518118D01*
G02X1525992Y38504I0J-7874D01*
G01Y16549D01*
G01X1018898Y114172D02*
Y54252D01*
G03X1026772Y46378I7874J0D01*
G01X1518118D01*
G02X1525992Y38504I0J-7874D01*
G01Y16549D01*
G01X1018898Y114172D02*
Y54252D01*
G03X1026772Y46378I7874J0D01*
G01X1518118D01*
G02X1525992Y38504I0J-7874D01*
G01Y16549D01*
G01X1018898Y114172D02*
Y54252D01*
G03X1026772Y46378I7874J0D01*
G01X1518118D01*
G02X1525992Y38504I0J-7874D01*
G01Y16549D01*
G01X1018898Y114172D02*
Y54252D01*
G03X1026772Y46378I7874J0D01*
G01X1518118D01*
G02X1525992Y38504I0J-7874D01*
G01Y16549D01*
G01X1018898Y114172D02*
Y54252D01*
G03X1026772Y46378I7874J0D01*
G01X1518118D01*
G02X1525992Y38504I0J-7874D01*
G01Y16549D01*
G01X1018898Y114172D02*
Y54252D01*
G03X1026772Y46378I7874J0D01*
G01X1518118D01*
G02X1525992Y38504I0J-7874D01*
G01Y16549D01*
G01X1018898Y114172D02*
Y54252D01*
G03X1026772Y46378I7874J0D01*
G01X1518118D01*
G02X1525992Y38504I0J-7874D01*
G01Y16549D01*
G01X1018898Y114172D02*
Y54252D01*
G03X1026772Y46378I7874J0D01*
G01X1518118D01*
G02X1525992Y38504I0J-7874D01*
G01Y16549D01*
G01X1018898Y114172D02*
Y54252D01*
G03X1026772Y46378I7874J0D01*
G01X1518118D01*
G02X1525992Y38504I0J-7874D01*
G01Y16549D01*
G01X1018898Y114172D02*
Y54252D01*
G03X1026772Y46378I7874J0D01*
G01X1518118D01*
G02X1525992Y38504I0J-7874D01*
G01Y16549D01*
G01X1018898Y114172D02*
Y54252D01*
G03X1026772Y46378I7874J0D01*
G01X1518118D01*
G02X1525992Y38504I0J-7874D01*
G01Y16549D01*
G01X1018898Y114172D02*
Y54252D01*
G03X1026772Y46378I7874J0D01*
G01X1518118D01*
G02X1525992Y38504I0J-7874D01*
G01Y16549D01*
G01X1018898Y114172D02*
Y54252D01*
G03X1026772Y46378I7874J0D01*
G01X1518118D01*
G02X1525992Y38504I0J-7874D01*
G01Y16549D01*
G01X1018898Y114172D02*
Y54252D01*
G03X1026772Y46378I7874J0D01*
G01X1518118D01*
G02X1525992Y38504I0J-7874D01*
G01Y16549D01*
G01X1018898Y114172D02*
Y54252D01*
G03X1026772Y46378I7874J0D01*
G01X1518118D01*
G02X1525992Y38504I0J-7874D01*
G01Y16549D01*
G01X1018898Y114172D02*
Y54252D01*
G03X1026772Y46378I7874J0D01*
G01X1518118D01*
G02X1525992Y38504I0J-7874D01*
G01Y16549D01*
G01X1018898Y114172D02*
Y54252D01*
G03X1026772Y46378I7874J0D01*
G01X1518118D01*
G02X1525992Y38504I0J-7874D01*
G01Y16549D01*
G01X1018898Y114172D02*
Y54252D01*
G03X1026772Y46378I7874J0D01*
G01X1518118D01*
G02X1525992Y38504I0J-7874D01*
G01Y16549D01*
G01X1018898Y114172D02*
Y54252D01*
G03X1026772Y46378I7874J0D01*
G01X1518118D01*
G02X1525992Y38504I0J-7874D01*
G01Y16549D01*
G01X1018898Y114172D02*
Y54252D01*
G03X1026772Y46378I7874J0D01*
G01X1518118D01*
G02X1525992Y38504I0J-7874D01*
G01Y16549D01*
G01X1018898Y114172D02*
Y54252D01*
G03X1026772Y46378I7874J0D01*
G01X1518118D01*
G02X1525992Y38504I0J-7874D01*
G01Y16549D01*
G01X1018898Y114172D02*
Y54252D01*
G03X1026772Y46378I7874J0D01*
G01X1518118D01*
G02X1525992Y38504I0J-7874D01*
G01Y16549D01*
G01X1018898Y114172D02*
Y54252D01*
G03X1026772Y46378I7874J0D01*
G01X1518118D01*
G02X1525992Y38504I0J-7874D01*
G01Y16549D01*
G01X1018898Y114172D02*
Y54252D01*
G03X1026772Y46378I7874J0D01*
G01X1518118D01*
G02X1525992Y38504I0J-7874D01*
G01Y16549D01*
G01X1018898Y114172D02*
Y54252D01*
G03X1026772Y46378I7874J0D01*
G01X1518118D01*
G02X1525992Y38504I0J-7874D01*
G01Y16549D01*
G01X1018898Y114172D02*
Y54252D01*
G03X1026772Y46378I7874J0D01*
G01X1518118D01*
G02X1525992Y38504I0J-7874D01*
G01Y16549D01*
G01X1018898Y114172D02*
Y54252D01*
G03X1026772Y46378I7874J0D01*
G01X1518118D01*
G02X1525992Y38504I0J-7874D01*
G01Y16549D01*
G01X1018898Y114172D02*
Y54252D01*
G03X1026772Y46378I7874J0D01*
G01X1518118D01*
G02X1525992Y38504I0J-7874D01*
G01Y16549D01*
G01X1018898Y114172D02*
Y54252D01*
G03X1026772Y46378I7874J0D01*
G01X1518118D01*
G02X1525992Y38504I0J-7874D01*
G01Y16549D01*
G01X1018898Y114172D02*
Y54252D01*
G03X1026772Y46378I7874J0D01*
G01X1518118D01*
G02X1525992Y38504I0J-7874D01*
G01Y16549D01*
G01X1018898Y114172D02*
Y54252D01*
G03X1026772Y46378I7874J0D01*
G01X1518118D01*
G02X1525992Y38504I0J-7874D01*
G01Y16549D01*
G01X1018898Y114172D02*
Y54252D01*
G03X1026772Y46378I7874J0D01*
G01X1518118D01*
G02X1525992Y38504I0J-7874D01*
G01Y16549D01*
G01X1007087Y134331D02*
G02X1011024Y130394I0J-3937D01*
G01X1016837Y1844196D02*
X1012187D01*
Y1856696D01*
X1016837D01*
G01X1065930Y38504D02*
G03Y46378I0J3937D01*
G01X1085616Y38504D02*
G02Y46378I0J3937D01*
G01X1796071Y16549D02*
Y38504D01*
G02X1803945Y46378I7874J0D01*
G01X1849606D01*
G03X1857480Y54252I0J7874D01*
G01Y305793D01*
G03X1855174Y311361I-7874J0D01*
G01X1846007Y320528D01*
G02X1843701Y326096I5568J5568D01*
G01Y1593982D01*
G03X1841395Y1599550I-7874J0D01*
G01X1834196Y1606749D01*
G02X1831890Y1612316I5567J5567D01*
G01Y1732244D01*
G03X1824016Y1740118I-7874J0D01*
G01X1091791D01*
G01X1796071Y16549D02*
Y38504D01*
G02X1803945Y46378I7874J0D01*
G01X1849606D01*
G03X1857480Y54252I0J7874D01*
G01Y305793D01*
G03X1855174Y311361I-7874J0D01*
G01X1846007Y320528D01*
G02X1843701Y326096I5568J5568D01*
G01Y1593982D01*
G03X1841395Y1599550I-7874J0D01*
G01X1834196Y1606749D01*
G02X1831890Y1612316I5567J5567D01*
G01Y1732244D01*
G03X1824016Y1740118I-7874J0D01*
G01X1091791D01*
G03X1089823Y1738149I0J-1968D01*
G01X1796071Y16549D02*
Y38504D01*
G02X1803945Y46378I7874J0D01*
G01X1849606D01*
G03X1857480Y54252I0J7874D01*
G01Y305793D01*
G03X1855174Y311361I-7874J0D01*
G01X1846007Y320528D01*
G02X1843701Y326096I5568J5568D01*
G01Y1593982D01*
G03X1841395Y1599550I-7874J0D01*
G01X1834196Y1606749D01*
G02X1831890Y1612316I5567J5567D01*
G01Y1732244D01*
G03X1824016Y1740118I-7874J0D01*
G01X1091791D01*
G03X1089823Y1738149I0J-1968D01*
G01Y1736890D01*
G01X1796071Y16549D02*
Y38504D01*
G02X1803945Y46378I7874J0D01*
G01X1849606D01*
G03X1857480Y54252I0J7874D01*
G01Y305793D01*
G03X1855174Y311361I-7874J0D01*
G01X1846007Y320528D01*
G02X1843701Y326096I5568J5568D01*
G01Y1593982D01*
G03X1841395Y1599550I-7874J0D01*
G01X1834196Y1606749D01*
G02X1831890Y1612316I5567J5567D01*
G01Y1732244D01*
G03X1824016Y1740118I-7874J0D01*
G01X1091791D01*
G03X1089823Y1738149I0J-1968D01*
G01Y1736890D01*
G02X1087854Y1734921I-1969J0D01*
G01X1796071Y16549D02*
Y38504D01*
G02X1803945Y46378I7874J0D01*
G01X1849606D01*
G03X1857480Y54252I0J7874D01*
G01Y305793D01*
G03X1855174Y311361I-7874J0D01*
G01X1846007Y320528D01*
G02X1843701Y326096I5568J5568D01*
G01Y1593982D01*
G03X1841395Y1599550I-7874J0D01*
G01X1834196Y1606749D01*
G02X1831890Y1612316I5567J5567D01*
G01Y1732244D01*
G03X1824016Y1740118I-7874J0D01*
G01X1091791D01*
G01X1796071Y16549D02*
Y38504D01*
G02X1803945Y46378I7874J0D01*
G01X1849606D01*
G03X1857480Y54252I0J7874D01*
G01Y305793D01*
G03X1855174Y311361I-7874J0D01*
G01X1846007Y320528D01*
G02X1843701Y326096I5568J5568D01*
G01Y1593982D01*
G03X1841395Y1599550I-7874J0D01*
G01X1834196Y1606749D01*
G02X1831890Y1612316I5567J5567D01*
G01Y1732244D01*
G03X1824016Y1740118I-7874J0D01*
G01X1091791D01*
G03X1089823Y1738149I0J-1968D01*
G01X1796071Y16549D02*
Y38504D01*
G02X1803945Y46378I7874J0D01*
G01X1849606D01*
G03X1857480Y54252I0J7874D01*
G01Y305793D01*
G03X1855174Y311361I-7874J0D01*
G01X1846007Y320528D01*
G02X1843701Y326096I5568J5568D01*
G01Y1593982D01*
G03X1841395Y1599550I-7874J0D01*
G01X1834196Y1606749D01*
G02X1831890Y1612316I5567J5567D01*
G01Y1732244D01*
G03X1824016Y1740118I-7874J0D01*
G01X1091791D01*
G03X1089823Y1738149I0J-1968D01*
G01Y1736890D01*
G01X1796071Y16549D02*
Y38504D01*
G02X1803945Y46378I7874J0D01*
G01X1849606D01*
G03X1857480Y54252I0J7874D01*
G01Y305793D01*
G03X1855174Y311361I-7874J0D01*
G01X1846007Y320528D01*
G02X1843701Y326096I5568J5568D01*
G01Y1593982D01*
G03X1841395Y1599550I-7874J0D01*
G01X1834196Y1606749D01*
G02X1831890Y1612316I5567J5567D01*
G01Y1732244D01*
G03X1824016Y1740118I-7874J0D01*
G01X1091791D01*
G03X1089823Y1738149I0J-1968D01*
G01Y1736890D01*
G02X1087854Y1734921I-1969J0D01*
G01X1085037Y1844196D02*
X1089687D01*
Y1856696D01*
X1085037D01*
G01X1106029Y1747992D02*
G02Y1740118I0J-3937D01*
G01X1108512Y1862946D02*
X2101574D01*
G01X1125715Y1747992D02*
G03Y1740118I0J-3937D01*
G01X1166558Y1747992D02*
G02Y1740118I0J-3937D01*
G01X1186244Y1747992D02*
G03Y1740118I0J-3937D01*
G01X1269725Y38504D02*
G03Y46378I0J3937D01*
G01X1289411Y38504D02*
G02Y46378I0J3937D01*
G01X1401230Y38504D02*
G03Y46378I0J3937D01*
G01X1420916Y38504D02*
G02Y46378I0J3937D01*
G01X1434552Y1755866D02*
Y1783576D01*
G01Y1755866D02*
G03X1442426Y1747992I7874J0D01*
G01X1474110D01*
G03X1481984Y1755866I0J7874D01*
G01X1452218Y1747992D02*
G02Y1740118I0J-3937D01*
G01X1471904Y1747992D02*
G03Y1740118I0J-3937D01*
G01X1481984Y1783576D02*
Y1755866D01*
G01Y1783576D02*
G02X1489858Y1791450I7874J0D01*
G01X1754370Y1747992D02*
X1655418D01*
G02X1647544Y1755866I0J7874D01*
G01Y1783576D01*
G03X1639670Y1791450I-7874J0D01*
G01X1489858D01*
G01X1525992Y8492D02*
Y1969D01*
G03X1527961Y0I1969J0D01*
G01X1525992Y8492D02*
Y1969D01*
G03X1527961Y0I1969J0D01*
G01X1794102D01*
G01X1525992Y8492D02*
Y1969D01*
G03X1527961Y0I1969J0D01*
G01X1794102D01*
G03X1796071Y1969I0J1969D01*
G01X1525992Y8492D02*
Y1969D01*
G03X1527961Y0I1969J0D01*
G01X1794102D01*
G03X1796071Y1969I0J1969D01*
G01Y8492D01*
G01X1525992D02*
Y1969D01*
G03X1527961Y0I1969J0D01*
G01X1794102D01*
G03X1796071Y1969I0J1969D01*
G01Y8492D01*
G01X1525992D02*
Y1969D01*
G03X1527961Y0I1969J0D01*
G01X1794102D01*
G03X1796071Y1969I0J1969D01*
G01Y8492D01*
G01X1525992D02*
Y1969D01*
G03X1527961Y0I1969J0D01*
G01X1794102D01*
G03X1796071Y1969I0J1969D01*
G01Y8492D01*
G01X1525992D02*
Y1969D01*
G03X1527961Y0I1969J0D01*
G01X1794102D01*
G03X1796071Y1969I0J1969D01*
G01Y8492D01*
G01X1525992D02*
Y1969D01*
G03X1527961Y0I1969J0D01*
G01X1794102D01*
G03X1796071Y1969I0J1969D01*
G01Y8492D01*
G01X1525992D02*
Y1969D01*
G03X1527961Y0I1969J0D01*
G01X1794102D01*
G03X1796071Y1969I0J1969D01*
G01Y8492D01*
G01X1525992D02*
Y1969D01*
G03X1527961Y0I1969J0D01*
G01X1794102D01*
G03X1796071Y1969I0J1969D01*
G01Y8492D01*
G01X1525992D02*
Y1969D01*
G03X1527961Y0I1969J0D01*
G01X1794102D01*
G03X1796071Y1969I0J1969D01*
G01Y8492D01*
G01X1525992D02*
Y1969D01*
G03X1527961Y0I1969J0D01*
G01X1794102D01*
G03X1796071Y1969I0J1969D01*
G01Y8492D01*
G01X1525992D02*
Y1969D01*
G03X1527961Y0I1969J0D01*
G01X1794102D01*
G03X1796071Y1969I0J1969D01*
G01Y8492D01*
G01X1525992D02*
Y1969D01*
G03X1527961Y0I1969J0D01*
G01X1794102D01*
G03X1796071Y1969I0J1969D01*
G01Y8492D01*
G01X1525992D02*
Y1969D01*
G03X1527961Y0I1969J0D01*
G01X1794102D01*
G03X1796071Y1969I0J1969D01*
G01Y8492D01*
G01X1525992D02*
Y1969D01*
G03X1527961Y0I1969J0D01*
G01X1794102D01*
G03X1796071Y1969I0J1969D01*
G01Y8492D01*
G01X1525992D02*
Y1969D01*
G03X1527961Y0I1969J0D01*
G01X1794102D01*
G03X1796071Y1969I0J1969D01*
G01Y8492D01*
G01X1525992D02*
Y1969D01*
G03X1527961Y0I1969J0D01*
G01X1794102D01*
G03X1796071Y1969I0J1969D01*
G01Y8492D01*
G01X1525992D02*
Y1969D01*
G03X1527961Y0I1969J0D01*
G01X1794102D01*
G03X1796071Y1969I0J1969D01*
G01Y8492D01*
G01X1525992D02*
Y1969D01*
G03X1527961Y0I1969J0D01*
G01X1794102D01*
G03X1796071Y1969I0J1969D01*
G01Y8492D01*
G01X1525992D02*
Y1969D01*
G03X1527961Y0I1969J0D01*
G01X1794102D01*
G03X1796071Y1969I0J1969D01*
G01Y8492D01*
G01X1525992D02*
Y1969D01*
G03X1527961Y0I1969J0D01*
G01X1794102D01*
G03X1796071Y1969I0J1969D01*
G01Y8492D01*
G01X1525992D02*
Y1969D01*
G03X1527961Y0I1969J0D01*
G01X1794102D01*
G03X1796071Y1969I0J1969D01*
G01Y8492D01*
G01X1525992D02*
Y1969D01*
G03X1527961Y0I1969J0D01*
G01X1794102D01*
G03X1796071Y1969I0J1969D01*
G01Y8492D01*
G01X1525992D02*
Y1969D01*
G03X1527961Y0I1969J0D01*
G01X1794102D01*
G03X1796071Y1969I0J1969D01*
G01Y8492D01*
G01X1525992D02*
Y1969D01*
G03X1527961Y0I1969J0D01*
G01X1794102D01*
G03X1796071Y1969I0J1969D01*
G01Y8492D01*
G01X1525992D02*
Y1969D01*
G03X1527961Y0I1969J0D01*
G01X1794102D01*
G03X1796071Y1969I0J1969D01*
G01Y8492D01*
G01X1525992D02*
Y1969D01*
G03X1527961Y0I1969J0D01*
G01X1794102D01*
G03X1796071Y1969I0J1969D01*
G01Y8492D01*
G01X1525992D02*
Y1969D01*
G03X1527961Y0I1969J0D01*
G01X1794102D01*
G03X1796071Y1969I0J1969D01*
G01Y8492D01*
G01X1525992D02*
Y1969D01*
G03X1527961Y0I1969J0D01*
G01X1794102D01*
G03X1796071Y1969I0J1969D01*
G01Y8492D01*
G01X1525992D02*
Y1969D01*
G03X1527961Y0I1969J0D01*
G01X1794102D01*
G03X1796071Y1969I0J1969D01*
G01Y8492D01*
G01X1525992D02*
Y1969D01*
G03X1527961Y0I1969J0D01*
G01X1794102D01*
G03X1796071Y1969I0J1969D01*
G01Y8492D01*
G01X1525992D02*
Y1969D01*
G03X1527961Y0I1969J0D01*
G01X1525992Y8492D02*
Y1969D01*
G03X1527961Y0I1969J0D01*
G01X1794102D01*
G01X1525992Y8492D02*
Y1969D01*
G03X1527961Y0I1969J0D01*
G01X1794102D01*
G03X1796071Y1969I0J1969D01*
G01X1525992Y8492D02*
Y1969D01*
G03X1527961Y0I1969J0D01*
G01X1794102D01*
G03X1796071Y1969I0J1969D01*
G01Y8492D01*
G01X1525992D02*
Y1969D01*
G03X1527961Y0I1969J0D01*
G01X1794102D01*
G03X1796071Y1969I0J1969D01*
G01Y8492D01*
G01X1525992D02*
Y1969D01*
G03X1527961Y0I1969J0D01*
G01X1794102D01*
G03X1796071Y1969I0J1969D01*
G01Y8492D01*
G01X1525992D02*
Y1969D01*
G03X1527961Y0I1969J0D01*
G01X1794102D01*
G03X1796071Y1969I0J1969D01*
G01Y8492D01*
G01X1525992D02*
Y1969D01*
G03X1527961Y0I1969J0D01*
G01X1794102D01*
G03X1796071Y1969I0J1969D01*
G01Y8492D01*
G01X1525992D02*
Y1969D01*
G03X1527961Y0I1969J0D01*
G01X1794102D01*
G03X1796071Y1969I0J1969D01*
G01Y8492D01*
G01X1525992D02*
Y1969D01*
G03X1527961Y0I1969J0D01*
G01X1794102D01*
G03X1796071Y1969I0J1969D01*
G01Y8492D01*
G01X1525992D02*
Y1969D01*
G03X1527961Y0I1969J0D01*
G01X1794102D01*
G03X1796071Y1969I0J1969D01*
G01Y8492D01*
G01X1525992D02*
Y1969D01*
G03X1527961Y0I1969J0D01*
G01X1794102D01*
G03X1796071Y1969I0J1969D01*
G01Y8492D01*
G01X1525992D02*
Y1969D01*
G03X1527961Y0I1969J0D01*
G01X1794102D01*
G03X1796071Y1969I0J1969D01*
G01Y8492D01*
G01X1525992D02*
Y1969D01*
G03X1527961Y0I1969J0D01*
G01X1794102D01*
G03X1796071Y1969I0J1969D01*
G01Y8492D01*
G01X1525992D02*
Y1969D01*
G03X1527961Y0I1969J0D01*
G01X1794102D01*
G03X1796071Y1969I0J1969D01*
G01Y8492D01*
G01X1525992D02*
Y1969D01*
G03X1527961Y0I1969J0D01*
G01X1794102D01*
G03X1796071Y1969I0J1969D01*
G01Y8492D01*
G01X1525992D02*
Y1969D01*
G03X1527961Y0I1969J0D01*
G01X1794102D01*
G03X1796071Y1969I0J1969D01*
G01Y8492D01*
G01X1525992D02*
Y1969D01*
G03X1527961Y0I1969J0D01*
G01X1794102D01*
G03X1796071Y1969I0J1969D01*
G01Y8492D01*
G01X1525992D02*
Y1969D01*
G03X1527961Y0I1969J0D01*
G01X1794102D01*
G03X1796071Y1969I0J1969D01*
G01Y8492D01*
G01X1525992D02*
Y1969D01*
G03X1527961Y0I1969J0D01*
G01X1794102D01*
G03X1796071Y1969I0J1969D01*
G01Y8492D01*
G01X1525992D02*
Y1969D01*
G03X1527961Y0I1969J0D01*
G01X1794102D01*
G03X1796071Y1969I0J1969D01*
G01Y8492D01*
G01X1525992D02*
Y1969D01*
G03X1527961Y0I1969J0D01*
G01X1794102D01*
G03X1796071Y1969I0J1969D01*
G01Y8492D01*
G01X1525992D02*
Y1969D01*
G03X1527961Y0I1969J0D01*
G01X1794102D01*
G03X1796071Y1969I0J1969D01*
G01Y8492D01*
G01X1525992D02*
Y1969D01*
G03X1527961Y0I1969J0D01*
G01X1794102D01*
G03X1796071Y1969I0J1969D01*
G01Y8492D01*
G01X1525992D02*
Y1969D01*
G03X1527961Y0I1969J0D01*
G01X1794102D01*
G03X1796071Y1969I0J1969D01*
G01Y8492D01*
G01X1525992D02*
Y1969D01*
G03X1527961Y0I1969J0D01*
G01X1794102D01*
G03X1796071Y1969I0J1969D01*
G01Y8492D01*
G01X1525992D02*
Y1969D01*
G03X1527961Y0I1969J0D01*
G01X1794102D01*
G03X1796071Y1969I0J1969D01*
G01Y8492D01*
G01X1525992D02*
Y1969D01*
G03X1527961Y0I1969J0D01*
G01X1794102D01*
G03X1796071Y1969I0J1969D01*
G01Y8492D01*
G01X1525992D02*
Y1969D01*
G03X1527961Y0I1969J0D01*
G01X1794102D01*
G03X1796071Y1969I0J1969D01*
G01Y8492D01*
G01X1525992D02*
Y1969D01*
G03X1527961Y0I1969J0D01*
G01X1794102D01*
G03X1796071Y1969I0J1969D01*
G01Y8492D01*
G01X1525992D02*
Y1969D01*
G03X1527961Y0I1969J0D01*
G01X1794102D01*
G03X1796071Y1969I0J1969D01*
G01Y8492D01*
G01X1525992D02*
Y1969D01*
G03X1527961Y0I1969J0D01*
G01X1794102D01*
G03X1796071Y1969I0J1969D01*
G01Y8492D01*
G01X1525992D02*
Y1969D01*
G03X1527961Y0I1969J0D01*
G01X1794102D01*
G03X1796071Y1969I0J1969D01*
G01Y8492D01*
G01X1525992D02*
Y1969D01*
G03X1527961Y0I1969J0D01*
G01X1794102D01*
G03X1796071Y1969I0J1969D01*
G01Y8492D01*
G01X1525992D02*
Y1969D01*
G01X1687442Y1747992D02*
G02Y1740118I0J-3937D01*
G01X1707128Y1747992D02*
G03Y1740118I0J-3937D01*
G01X1775695Y1747992D02*
G02Y1740118I0J-3937D01*
G01X1795381Y1747992D02*
G03Y1740118I0J-3937D01*
G01X1796071Y16549D02*
Y38504D01*
G01Y16549D02*
Y38504D01*
G02X1803945Y46378I7874J0D01*
G01X1796071Y16549D02*
Y38504D01*
G02X1803945Y46378I7874J0D01*
G01X1849606D01*
G01X1796071Y16549D02*
Y38504D01*
G02X1803945Y46378I7874J0D01*
G01X1849606D01*
G03X1857480Y54252I0J7874D01*
G01X1796071Y16549D02*
Y38504D01*
G02X1803945Y46378I7874J0D01*
G01X1849606D01*
G03X1857480Y54252I0J7874D01*
G01Y305793D01*
G01X1796071Y16549D02*
Y38504D01*
G02X1803945Y46378I7874J0D01*
G01X1849606D01*
G03X1857480Y54252I0J7874D01*
G01Y305793D01*
G03X1855174Y311361I-7874J0D01*
G01X1796071Y16549D02*
Y38504D01*
G02X1803945Y46378I7874J0D01*
G01X1849606D01*
G03X1857480Y54252I0J7874D01*
G01Y305793D01*
G03X1855174Y311361I-7874J0D01*
G01X1846007Y320528D01*
G01X1796071Y16549D02*
Y38504D01*
G02X1803945Y46378I7874J0D01*
G01X1849606D01*
G03X1857480Y54252I0J7874D01*
G01Y305793D01*
G03X1855174Y311361I-7874J0D01*
G01X1846007Y320528D01*
G02X1843701Y326096I5568J5568D01*
G01X1796071Y16549D02*
Y38504D01*
G02X1803945Y46378I7874J0D01*
G01X1849606D01*
G03X1857480Y54252I0J7874D01*
G01Y305793D01*
G03X1855174Y311361I-7874J0D01*
G01X1846007Y320528D01*
G02X1843701Y326096I5568J5568D01*
G01Y1593982D01*
G01X1796071Y16549D02*
Y38504D01*
G02X1803945Y46378I7874J0D01*
G01X1849606D01*
G03X1857480Y54252I0J7874D01*
G01Y305793D01*
G03X1855174Y311361I-7874J0D01*
G01X1846007Y320528D01*
G02X1843701Y326096I5568J5568D01*
G01Y1593982D01*
G03X1841395Y1599550I-7874J0D01*
G01X1796071Y16549D02*
Y38504D01*
G02X1803945Y46378I7874J0D01*
G01X1849606D01*
G03X1857480Y54252I0J7874D01*
G01Y305793D01*
G03X1855174Y311361I-7874J0D01*
G01X1846007Y320528D01*
G02X1843701Y326096I5568J5568D01*
G01Y1593982D01*
G03X1841395Y1599550I-7874J0D01*
G01X1834196Y1606749D01*
G01X1796071Y16549D02*
Y38504D01*
G02X1803945Y46378I7874J0D01*
G01X1849606D01*
G03X1857480Y54252I0J7874D01*
G01Y305793D01*
G03X1855174Y311361I-7874J0D01*
G01X1846007Y320528D01*
G02X1843701Y326096I5568J5568D01*
G01Y1593982D01*
G03X1841395Y1599550I-7874J0D01*
G01X1834196Y1606749D01*
G02X1831890Y1612316I5567J5567D01*
G01X1796071Y16549D02*
Y38504D01*
G02X1803945Y46378I7874J0D01*
G01X1849606D01*
G03X1857480Y54252I0J7874D01*
G01Y305793D01*
G03X1855174Y311361I-7874J0D01*
G01X1846007Y320528D01*
G02X1843701Y326096I5568J5568D01*
G01Y1593982D01*
G03X1841395Y1599550I-7874J0D01*
G01X1834196Y1606749D01*
G02X1831890Y1612316I5567J5567D01*
G01Y1732244D01*
G01X1796071Y16549D02*
Y38504D01*
G02X1803945Y46378I7874J0D01*
G01X1849606D01*
G03X1857480Y54252I0J7874D01*
G01Y305793D01*
G03X1855174Y311361I-7874J0D01*
G01X1846007Y320528D01*
G02X1843701Y326096I5568J5568D01*
G01Y1593982D01*
G03X1841395Y1599550I-7874J0D01*
G01X1834196Y1606749D01*
G02X1831890Y1612316I5567J5567D01*
G01Y1732244D01*
G03X1824016Y1740118I-7874J0D01*
G01X1796071Y16549D02*
Y38504D01*
G01Y16549D02*
Y38504D01*
G02X1803945Y46378I7874J0D01*
G01X1796071Y16549D02*
Y38504D01*
G02X1803945Y46378I7874J0D01*
G01X1849606D01*
G01X1796071Y16549D02*
Y38504D01*
G02X1803945Y46378I7874J0D01*
G01X1849606D01*
G03X1857480Y54252I0J7874D01*
G01X1796071Y16549D02*
Y38504D01*
G02X1803945Y46378I7874J0D01*
G01X1849606D01*
G03X1857480Y54252I0J7874D01*
G01Y305793D01*
G01X1796071Y16549D02*
Y38504D01*
G02X1803945Y46378I7874J0D01*
G01X1849606D01*
G03X1857480Y54252I0J7874D01*
G01Y305793D01*
G03X1855174Y311361I-7874J0D01*
G01X1796071Y16549D02*
Y38504D01*
G02X1803945Y46378I7874J0D01*
G01X1849606D01*
G03X1857480Y54252I0J7874D01*
G01Y305793D01*
G03X1855174Y311361I-7874J0D01*
G01X1846007Y320528D01*
G01X1796071Y16549D02*
Y38504D01*
G02X1803945Y46378I7874J0D01*
G01X1849606D01*
G03X1857480Y54252I0J7874D01*
G01Y305793D01*
G03X1855174Y311361I-7874J0D01*
G01X1846007Y320528D01*
G02X1843701Y326096I5568J5568D01*
G01X1796071Y16549D02*
Y38504D01*
G02X1803945Y46378I7874J0D01*
G01X1849606D01*
G03X1857480Y54252I0J7874D01*
G01Y305793D01*
G03X1855174Y311361I-7874J0D01*
G01X1846007Y320528D01*
G02X1843701Y326096I5568J5568D01*
G01Y1593982D01*
G01X1796071Y16549D02*
Y38504D01*
G02X1803945Y46378I7874J0D01*
G01X1849606D01*
G03X1857480Y54252I0J7874D01*
G01Y305793D01*
G03X1855174Y311361I-7874J0D01*
G01X1846007Y320528D01*
G02X1843701Y326096I5568J5568D01*
G01Y1593982D01*
G03X1841395Y1599550I-7874J0D01*
G01X1796071Y16549D02*
Y38504D01*
G02X1803945Y46378I7874J0D01*
G01X1849606D01*
G03X1857480Y54252I0J7874D01*
G01Y305793D01*
G03X1855174Y311361I-7874J0D01*
G01X1846007Y320528D01*
G02X1843701Y326096I5568J5568D01*
G01Y1593982D01*
G03X1841395Y1599550I-7874J0D01*
G01X1834196Y1606749D01*
G01X1796071Y16549D02*
Y38504D01*
G02X1803945Y46378I7874J0D01*
G01X1849606D01*
G03X1857480Y54252I0J7874D01*
G01Y305793D01*
G03X1855174Y311361I-7874J0D01*
G01X1846007Y320528D01*
G02X1843701Y326096I5568J5568D01*
G01Y1593982D01*
G03X1841395Y1599550I-7874J0D01*
G01X1834196Y1606749D01*
G02X1831890Y1612316I5567J5567D01*
G01X1796071Y16549D02*
Y38504D01*
G02X1803945Y46378I7874J0D01*
G01X1849606D01*
G03X1857480Y54252I0J7874D01*
G01Y305793D01*
G03X1855174Y311361I-7874J0D01*
G01X1846007Y320528D01*
G02X1843701Y326096I5568J5568D01*
G01Y1593982D01*
G03X1841395Y1599550I-7874J0D01*
G01X1834196Y1606749D01*
G02X1831890Y1612316I5567J5567D01*
G01Y1732244D01*
G01X1796071Y16549D02*
Y38504D01*
G02X1803945Y46378I7874J0D01*
G01X1849606D01*
G03X1857480Y54252I0J7874D01*
G01Y305793D01*
G03X1855174Y311361I-7874J0D01*
G01X1846007Y320528D01*
G02X1843701Y326096I5568J5568D01*
G01Y1593982D01*
G03X1841395Y1599550I-7874J0D01*
G01X1834196Y1606749D01*
G02X1831890Y1612316I5567J5567D01*
G01Y1732244D01*
G03X1824016Y1740118I-7874J0D01*
G01X1820208Y38504D02*
G03Y46378I0J3937D01*
G01X1839894Y38504D02*
G02Y46378I0J3937D01*
G01X2040574Y1822946D02*
X1873228D01*
G03X1865354Y1815072I0J-7874D01*
G01Y1747992D01*
G02X1857480Y1740118I-7874J0D01*
G01X1847638D01*
G03X1839764Y1732244I0J-7874D01*
G01Y1615579D01*
G03X1842070Y1610011I7874J0D01*
G01X1846963Y1605118D01*
G02X1851575Y1593983I-11134J-11134D01*
G01Y329357D01*
G03X1853882Y323789I7874J0D01*
G01X1860742Y316929D01*
G02X1865354Y305794I-11134J-11134D01*
G01Y-40945D01*
G03X1873228Y-48819I7874J0D01*
G01X2070078D01*
G01X1831890Y1642200D02*
G02X1839764I3937J0D01*
G01X1831890Y1661886D02*
G03X1839764I3937J0D01*
G01X1851575Y409690D02*
G03X1843701I-3937J0D01*
G01X1851575Y429376D02*
G02X1843701I-3937J0D01*
G01Y554405D02*
G02X1851575I3937J0D01*
G01X1843701Y574091D02*
G03X1851575I3937J0D01*
G01X1843701Y744247D02*
G02X1851575I3937J0D01*
G01X1843701Y763933D02*
G03X1851575I3937J0D01*
G01X1843701Y981548D02*
G02X1851575I3937J0D01*
G01X1843701Y1001234D02*
G03X1851575I3937J0D01*
G01X1843701Y1240477D02*
G02X1851575I3937J0D01*
G01X1843701Y1260163D02*
G03X1851575I3937J0D01*
G01X1843701Y1466161D02*
G02X1851575I3937J0D01*
G01X1843701Y1485847D02*
G03X1851575I3937J0D01*
G01X1857480Y-19863D02*
G02X1865354I3937J0D01*
G01X1857480Y-177D02*
G03X1865354I3937J0D01*
G01Y238549D02*
G03X1857480I-3937J0D01*
G01X1865354Y258235D02*
G02X1857480I-3937J0D01*
G01Y1775016D02*
G02X1865354I3937J0D01*
G01X1857480Y1794702D02*
G03X1865354I3937J0D01*
G01X2023700Y1229954D02*
G03X2031574Y1222080I7874J0D01*
G01D02*
X2093700D01*
G01X2101574Y1791450D02*
G02X2093700Y1783576I-7874J0D01*
G01X2031574D01*
G03X2023700Y1775702I0J-7874D01*
G01Y1229954D01*
G01X2101574Y1767828D02*
Y1237828D01*
X2031574D01*
Y1767828D01*
G01X2101574Y1237828D02*
G02X2093700Y1229954I-7874J0D01*
G01X2039448D01*
G02X2031574Y1237828I0J7874D01*
G01Y1302828D02*
X2101574D01*
G01X2031574Y1367390D02*
G03X2023700I-3937J0D01*
G01X2026456Y1383138D02*
G03I-1575J0D01*
G01Y1375264D02*
G03I-1575J0D01*
G01Y1391012D02*
G03I-1575J0D01*
G01Y1398886D02*
G03I-1575J0D01*
G01X2031574Y1406760D02*
G02X2023700I-3937J0D01*
G01X2031574Y1667390D02*
G03X2023700I-3937J0D01*
G01X2026456Y1683138D02*
G03I-1575J0D01*
G01Y1675264D02*
G03I-1575J0D01*
G01Y1691012D02*
G03I-1575J0D01*
G01Y1698886D02*
G03I-1575J0D01*
G01X2031574Y1706760D02*
G02X2023700I-3937J0D01*
G01X2031574Y1767828D02*
X2101574D01*
G01D02*
G03X2093700Y1775702I-7874J0D01*
G01X2039448D01*
G03X2031574Y1767828I0J-7874D01*
G01X2022574Y1822946D02*
X2093700D01*
G02X2101574Y1815072I0J-7874D01*
G01Y1799324D01*
G01X2047692Y1229954D02*
G02Y1222080I0J-3937D01*
G01X2044490Y1775702D02*
G03Y1783576I0J3937D01*
G01X2093700Y1822946D02*
X2040574D01*
G01X2065015Y1223261D02*
G03I-1575J0D01*
G01X2057141D02*
G03I-1575J0D01*
G01X2053939Y1782395D02*
G03I-1575J0D01*
G01X2061813D02*
G03I-1575J0D01*
G01X2093700Y-48819D02*
X2070078D01*
G01X2072889Y1223261D02*
G03I-1575J0D01*
G01X2080763D02*
G03I-1575J0D01*
G01X2077561Y1782395D02*
G03I-1575J0D01*
G01X2069687D02*
G03I-1575J0D01*
G01X2101574Y-40945D02*
G02X2093700Y-48819I-7874J0D01*
G01X2101574Y1159083D02*
Y1214206D01*
G03X2093700Y1222080I-7874J0D01*
G01X2087062Y1229954D02*
G03Y1222080I0J-3937D01*
G01X2083860Y1775702D02*
G02Y1783576I0J3937D01*
G01X2101574Y1815072D02*
G03X2093700Y1822946I-7874J0D01*
G01X2101574Y-40945D02*
Y44466D01*
G01Y-4796D02*
Y126550D01*
G01Y82156D02*
Y1211966D01*
G01Y1815072D02*
Y1791450D01*
G01Y1803846D02*
Y1815072D01*
G01Y1832789D02*
Y1872576D01*
G01Y1832946D02*
Y1872946D01*
G01X2094574Y1861446D02*
X2101574Y1862946D01*
X2094574Y1864446D01*
Y1861446D01*
G01X2111574Y-48819D02*
X2151574D01*
G01X2111574Y1822946D02*
X2151574D01*
G01X2141574Y829339D02*
Y-48819D01*
G01X2140074Y-41819D02*
X2141574Y-48819D01*
X2143074Y-41819D01*
X2140074D01*
G01X2160324Y846914D02*
Y842264D01*
X2147824D01*
Y846914D01*
G01X2160324Y927514D02*
Y932164D01*
X2147824D01*
Y927514D01*
G01X2141574Y944789D02*
Y1822946D01*
G01X2143074Y1815946D02*
X2141574Y1822946D01*
X2140074Y1815946D01*
X2143074D01*
G01X2207760Y45100D02*
X2208013Y45350D01*
X2208203Y45766D01*
X2208330Y46350D01*
X2208203Y46850D01*
X2207950Y47183D01*
X2207506Y47433D01*
X2205796D01*
Y42433D01*
X2207886D01*
X2208330Y42766D01*
X2208583Y43266D01*
X2208710Y43850D01*
X2208583Y44433D01*
X2208203Y44933D01*
X2207760Y45100D01*
X2205796D01*
G01X2211466Y42433D02*
Y45766D01*
G01Y45100D02*
X2211783Y45433D01*
X2212100Y45683D01*
X2212543Y45766D01*
X2212860Y45683D01*
X2213240Y45433D01*
G01X2216503Y44683D02*
X2218530D01*
X2218340Y45266D01*
X2218023Y45600D01*
X2217580Y45766D01*
X2217136Y45683D01*
X2216756Y45433D01*
X2216503Y44850D01*
X2216376Y44350D01*
Y43850D01*
X2216503Y43350D01*
X2216820Y42850D01*
X2217200Y42516D01*
X2217643Y42433D01*
X2218086Y42600D01*
X2218530Y43100D01*
G01X2223693Y42433D02*
Y45766D01*
G01Y45183D02*
X2223440Y45516D01*
X2223060Y45683D01*
X2222616Y45766D01*
X2222173Y45600D01*
X2221793Y45266D01*
X2221540Y44766D01*
X2221413Y44100D01*
X2221540Y43433D01*
X2221793Y42933D01*
X2222173Y42600D01*
X2222616Y42433D01*
X2223060Y42516D01*
X2223440Y42766D01*
X2223693Y43100D01*
G01X2226576Y42433D02*
Y47433D01*
G01X2228603Y45766D02*
X2226576Y43850D01*
G01X2227400Y44600D02*
X2228730Y42433D01*
G01X2232753Y47433D02*
Y42433D01*
G01X2231866Y45766D02*
X2233640D01*
G01X2238993Y42433D02*
Y45766D01*
G01Y45183D02*
X2238740Y45516D01*
X2238360Y45683D01*
X2237916Y45766D01*
X2237473Y45600D01*
X2237093Y45266D01*
X2236840Y44766D01*
X2236713Y44100D01*
X2236840Y43433D01*
X2237093Y42933D01*
X2237473Y42600D01*
X2237916Y42433D01*
X2238360Y42516D01*
X2238740Y42766D01*
X2238993Y43100D01*
G01X2241813Y42433D02*
Y47433D01*
G01Y44933D02*
X2242130Y45433D01*
X2242510Y45683D01*
X2242890Y45766D01*
X2243460Y45600D01*
X2243840Y45266D01*
X2244093Y44683D01*
Y44016D01*
X2243966Y43350D01*
X2243713Y42850D01*
X2243270Y42516D01*
X2242890Y42433D01*
X2242510Y42516D01*
X2242130Y42766D01*
X2241813Y43183D01*
G01X2248053Y42266D02*
X2247926Y42350D01*
Y42516D01*
X2248053Y42600D01*
X2248180Y42516D01*
Y42350D01*
X2248053Y42266D01*
G01Y44516D02*
X2247926Y44600D01*
Y44766D01*
X2248053Y44850D01*
X2248180Y44766D01*
Y44600D01*
X2248053Y44516D01*
G01X2282550Y108963D02*
Y113963D01*
X2284956D01*
G01X2284070Y111546D02*
X2282550D01*
G01X2288853Y108963D02*
X2288473Y109046D01*
X2288093Y109380D01*
X2287840Y109963D01*
X2287713Y110630D01*
X2287840Y111296D01*
X2288093Y111880D01*
X2288473Y112213D01*
X2288853Y112296D01*
X2289233Y112213D01*
X2289613Y111880D01*
X2289866Y111296D01*
X2289930Y110630D01*
X2289866Y109963D01*
X2289613Y109380D01*
X2289233Y109046D01*
X2288853Y108963D01*
G01X2293066D02*
Y112296D01*
G01Y111630D02*
X2293383Y111963D01*
X2293700Y112213D01*
X2294143Y112296D01*
X2294460Y112213D01*
X2294840Y111963D01*
G01X2302886Y108963D02*
Y113963D01*
X2304406D01*
X2304913Y113713D01*
X2305293Y113130D01*
X2305420Y112463D01*
X2305293Y111796D01*
X2304976Y111296D01*
X2304406Y111046D01*
X2302886D01*
G01X2310393Y108963D02*
Y112296D01*
G01Y111713D02*
X2310140Y112046D01*
X2309760Y112213D01*
X2309316Y112296D01*
X2308873Y112130D01*
X2308493Y111796D01*
X2308240Y111296D01*
X2308113Y110630D01*
X2308240Y109963D01*
X2308493Y109463D01*
X2308873Y109130D01*
X2309316Y108963D01*
X2309760Y109046D01*
X2310140Y109296D01*
X2310393Y109630D01*
G01X2313276Y108963D02*
Y112296D01*
G01Y111463D02*
X2313530Y111880D01*
X2313910Y112213D01*
X2314416Y112296D01*
X2314860Y112213D01*
X2315240Y111880D01*
X2315430Y111296D01*
Y108963D01*
G01X2318503Y111213D02*
X2320530D01*
X2320340Y111796D01*
X2320023Y112130D01*
X2319580Y112296D01*
X2319136Y112213D01*
X2318756Y111963D01*
X2318503Y111380D01*
X2318376Y110880D01*
Y110380D01*
X2318503Y109880D01*
X2318820Y109380D01*
X2319200Y109046D01*
X2319643Y108963D01*
X2320086Y109130D01*
X2320530Y109630D01*
G01X2324553Y108963D02*
Y113963D01*
G01X2335260Y111630D02*
X2335513Y111880D01*
X2335703Y112296D01*
X2335830Y112880D01*
X2335703Y113380D01*
X2335450Y113713D01*
X2335006Y113963D01*
X2333296D01*
Y108963D01*
X2335386D01*
X2335830Y109296D01*
X2336083Y109796D01*
X2336210Y110380D01*
X2336083Y110963D01*
X2335703Y111463D01*
X2335260Y111630D01*
X2333296D01*
G01X2339853Y108963D02*
X2339473Y109046D01*
X2339093Y109380D01*
X2338840Y109963D01*
X2338713Y110630D01*
X2338840Y111296D01*
X2339093Y111880D01*
X2339473Y112213D01*
X2339853Y112296D01*
X2340233Y112213D01*
X2340613Y111880D01*
X2340866Y111296D01*
X2340930Y110630D01*
X2340866Y109963D01*
X2340613Y109380D01*
X2340233Y109046D01*
X2339853Y108963D01*
G01X2346093D02*
Y112296D01*
G01Y111713D02*
X2345840Y112046D01*
X2345460Y112213D01*
X2345016Y112296D01*
X2344573Y112130D01*
X2344193Y111796D01*
X2343940Y111296D01*
X2343813Y110630D01*
X2343940Y109963D01*
X2344193Y109463D01*
X2344573Y109130D01*
X2345016Y108963D01*
X2345460Y109046D01*
X2345840Y109296D01*
X2346093Y109630D01*
G01X2349166Y108963D02*
Y112296D01*
G01Y111630D02*
X2349483Y111963D01*
X2349800Y112213D01*
X2350243Y112296D01*
X2350560Y112213D01*
X2350940Y111963D01*
G01X2356293Y113963D02*
Y108963D01*
G01Y109713D02*
X2356040Y109296D01*
X2355660Y109046D01*
X2355216Y108963D01*
X2354710Y109130D01*
X2354330Y109546D01*
X2354076Y110046D01*
X2354013Y110630D01*
X2354076Y111213D01*
X2354330Y111713D01*
X2354710Y112130D01*
X2355216Y112296D01*
X2355660Y112213D01*
X2355976Y112046D01*
X2356293Y111713D01*
G01X2283753Y126563D02*
Y121563D01*
G01X2282296Y126563D02*
X2285210D01*
G01X2288853Y121563D02*
X2288473Y121646D01*
X2288093Y121980D01*
X2287840Y122563D01*
X2287713Y123230D01*
X2287840Y123896D01*
X2288093Y124480D01*
X2288473Y124813D01*
X2288853Y124896D01*
X2289233Y124813D01*
X2289613Y124480D01*
X2289866Y123896D01*
X2289930Y123230D01*
X2289866Y122563D01*
X2289613Y121980D01*
X2289233Y121646D01*
X2288853Y121563D01*
G01X2292813Y119896D02*
Y124896D01*
G01Y124146D02*
X2293130Y124563D01*
X2293446Y124813D01*
X2293953Y124896D01*
X2294396Y124813D01*
X2294840Y124396D01*
X2295030Y123813D01*
X2295093Y123230D01*
X2295030Y122646D01*
X2294840Y122063D01*
X2294460Y121730D01*
X2293953Y121563D01*
X2293510Y121646D01*
X2293066Y121896D01*
X2292813Y122230D01*
G01X2302570Y121563D02*
X2304153Y126563D01*
X2305736Y121563D01*
G01X2305166Y123313D02*
X2303140D01*
G01X2308176Y121563D02*
Y124896D01*
G01Y124063D02*
X2308430Y124480D01*
X2308810Y124813D01*
X2309316Y124896D01*
X2309760Y124813D01*
X2310140Y124480D01*
X2310330Y123896D01*
Y121563D01*
G01X2315493Y126563D02*
Y121563D01*
G01Y122313D02*
X2315240Y121896D01*
X2314860Y121646D01*
X2314416Y121563D01*
X2313910Y121730D01*
X2313530Y122146D01*
X2313276Y122646D01*
X2313213Y123230D01*
X2313276Y123813D01*
X2313530Y124313D01*
X2313910Y124730D01*
X2314416Y124896D01*
X2314860Y124813D01*
X2315176Y124646D01*
X2315493Y124313D01*
G01X2325060Y124230D02*
X2325313Y124480D01*
X2325503Y124896D01*
X2325630Y125480D01*
X2325503Y125980D01*
X2325250Y126313D01*
X2324806Y126563D01*
X2323096D01*
Y121563D01*
X2325186D01*
X2325630Y121896D01*
X2325883Y122396D01*
X2326010Y122980D01*
X2325883Y123563D01*
X2325503Y124063D01*
X2325060Y124230D01*
X2323096D01*
G01X2329653Y121563D02*
X2329273Y121646D01*
X2328893Y121980D01*
X2328640Y122563D01*
X2328513Y123230D01*
X2328640Y123896D01*
X2328893Y124480D01*
X2329273Y124813D01*
X2329653Y124896D01*
X2330033Y124813D01*
X2330413Y124480D01*
X2330666Y123896D01*
X2330730Y123230D01*
X2330666Y122563D01*
X2330413Y121980D01*
X2330033Y121646D01*
X2329653Y121563D01*
G01X2334753Y126563D02*
Y121563D01*
G01X2333866Y124896D02*
X2335640D01*
G01X2339853Y126563D02*
Y121563D01*
G01X2338966Y124896D02*
X2340740D01*
G01X2344953Y121563D02*
X2344573Y121646D01*
X2344193Y121980D01*
X2343940Y122563D01*
X2343813Y123230D01*
X2343940Y123896D01*
X2344193Y124480D01*
X2344573Y124813D01*
X2344953Y124896D01*
X2345333Y124813D01*
X2345713Y124480D01*
X2345966Y123896D01*
X2346030Y123230D01*
X2345966Y122563D01*
X2345713Y121980D01*
X2345333Y121646D01*
X2344953Y121563D01*
G01X2348153D02*
Y124896D01*
G01Y123980D02*
X2348343Y124396D01*
X2348660Y124730D01*
X2349103Y124896D01*
X2349546Y124730D01*
X2349863Y124396D01*
X2350053Y123980D01*
Y121563D01*
G01Y123980D02*
X2350243Y124396D01*
X2350560Y124730D01*
X2351003Y124896D01*
X2351446Y124730D01*
X2351763Y124396D01*
X2351953Y123896D01*
Y121563D01*
G01X2358923Y122230D02*
X2359430Y121813D01*
X2360000Y121563D01*
X2360506D01*
X2361013Y121813D01*
X2361393Y122230D01*
X2361583Y122813D01*
X2361456Y123396D01*
X2361140Y123896D01*
X2360570Y124230D01*
X2359810Y124396D01*
X2359366Y124730D01*
X2359176Y125313D01*
X2359303Y125896D01*
X2359620Y126313D01*
X2360063Y126563D01*
X2360506D01*
X2360950Y126396D01*
X2361330Y125980D01*
G01X2365353Y124896D02*
Y121563D01*
G01Y126230D02*
X2365226Y126313D01*
Y126480D01*
X2365353Y126563D01*
X2365480Y126480D01*
Y126313D01*
X2365353Y126230D01*
G01X2371593Y126563D02*
Y121563D01*
G01Y122313D02*
X2371340Y121896D01*
X2370960Y121646D01*
X2370516Y121563D01*
X2370010Y121730D01*
X2369630Y122146D01*
X2369376Y122646D01*
X2369313Y123230D01*
X2369376Y123813D01*
X2369630Y124313D01*
X2370010Y124730D01*
X2370516Y124896D01*
X2370960Y124813D01*
X2371276Y124646D01*
X2371593Y124313D01*
G01X2374603Y123813D02*
X2376630D01*
X2376440Y124396D01*
X2376123Y124730D01*
X2375680Y124896D01*
X2375236Y124813D01*
X2374856Y124563D01*
X2374603Y123980D01*
X2374476Y123480D01*
Y122980D01*
X2374603Y122480D01*
X2374920Y121980D01*
X2375300Y121646D01*
X2375743Y121563D01*
X2376186Y121730D01*
X2376630Y122230D01*
G01X2282550Y108963D02*
Y113963D01*
X2284956D01*
G01X2284070Y111546D02*
X2282550D01*
G01X2288853Y108963D02*
X2288473Y109046D01*
X2288093Y109380D01*
X2287840Y109963D01*
X2287713Y110630D01*
X2287840Y111296D01*
X2288093Y111880D01*
X2288473Y112213D01*
X2288853Y112296D01*
X2289233Y112213D01*
X2289613Y111880D01*
X2289866Y111296D01*
X2289930Y110630D01*
X2289866Y109963D01*
X2289613Y109380D01*
X2289233Y109046D01*
X2288853Y108963D01*
G01X2293066D02*
Y112296D01*
G01Y111630D02*
X2293383Y111963D01*
X2293700Y112213D01*
X2294143Y112296D01*
X2294460Y112213D01*
X2294840Y111963D01*
G01X2302886Y108963D02*
Y113963D01*
X2304406D01*
X2304913Y113713D01*
X2305293Y113130D01*
X2305420Y112463D01*
X2305293Y111796D01*
X2304976Y111296D01*
X2304406Y111046D01*
X2302886D01*
G01X2310393Y108963D02*
Y112296D01*
G01Y111713D02*
X2310140Y112046D01*
X2309760Y112213D01*
X2309316Y112296D01*
X2308873Y112130D01*
X2308493Y111796D01*
X2308240Y111296D01*
X2308113Y110630D01*
X2308240Y109963D01*
X2308493Y109463D01*
X2308873Y109130D01*
X2309316Y108963D01*
X2309760Y109046D01*
X2310140Y109296D01*
X2310393Y109630D01*
G01X2313276Y108963D02*
Y112296D01*
G01Y111463D02*
X2313530Y111880D01*
X2313910Y112213D01*
X2314416Y112296D01*
X2314860Y112213D01*
X2315240Y111880D01*
X2315430Y111296D01*
Y108963D01*
G01X2318503Y111213D02*
X2320530D01*
X2320340Y111796D01*
X2320023Y112130D01*
X2319580Y112296D01*
X2319136Y112213D01*
X2318756Y111963D01*
X2318503Y111380D01*
X2318376Y110880D01*
Y110380D01*
X2318503Y109880D01*
X2318820Y109380D01*
X2319200Y109046D01*
X2319643Y108963D01*
X2320086Y109130D01*
X2320530Y109630D01*
G01X2324553Y108963D02*
Y113963D01*
G01X2335260Y111630D02*
X2335513Y111880D01*
X2335703Y112296D01*
X2335830Y112880D01*
X2335703Y113380D01*
X2335450Y113713D01*
X2335006Y113963D01*
X2333296D01*
Y108963D01*
X2335386D01*
X2335830Y109296D01*
X2336083Y109796D01*
X2336210Y110380D01*
X2336083Y110963D01*
X2335703Y111463D01*
X2335260Y111630D01*
X2333296D01*
G01X2339853Y108963D02*
X2339473Y109046D01*
X2339093Y109380D01*
X2338840Y109963D01*
X2338713Y110630D01*
X2338840Y111296D01*
X2339093Y111880D01*
X2339473Y112213D01*
X2339853Y112296D01*
X2340233Y112213D01*
X2340613Y111880D01*
X2340866Y111296D01*
X2340930Y110630D01*
X2340866Y109963D01*
X2340613Y109380D01*
X2340233Y109046D01*
X2339853Y108963D01*
G01X2346093D02*
Y112296D01*
G01Y111713D02*
X2345840Y112046D01*
X2345460Y112213D01*
X2345016Y112296D01*
X2344573Y112130D01*
X2344193Y111796D01*
X2343940Y111296D01*
X2343813Y110630D01*
X2343940Y109963D01*
X2344193Y109463D01*
X2344573Y109130D01*
X2345016Y108963D01*
X2345460Y109046D01*
X2345840Y109296D01*
X2346093Y109630D01*
G01X2349166Y108963D02*
Y112296D01*
G01Y111630D02*
X2349483Y111963D01*
X2349800Y112213D01*
X2350243Y112296D01*
X2350560Y112213D01*
X2350940Y111963D01*
G01X2356293Y113963D02*
Y108963D01*
G01Y109713D02*
X2356040Y109296D01*
X2355660Y109046D01*
X2355216Y108963D01*
X2354710Y109130D01*
X2354330Y109546D01*
X2354076Y110046D01*
X2354013Y110630D01*
X2354076Y111213D01*
X2354330Y111713D01*
X2354710Y112130D01*
X2355216Y112296D01*
X2355660Y112213D01*
X2355976Y112046D01*
X2356293Y111713D01*
G01X2282360Y134163D02*
Y139163D01*
X2283626D01*
X2284133Y138913D01*
X2284513Y138580D01*
X2284830Y138080D01*
X2285083Y137496D01*
X2285146Y136663D01*
X2285083Y135830D01*
X2284830Y135246D01*
X2284513Y134746D01*
X2284133Y134413D01*
X2283626Y134163D01*
X2282360D01*
G01X2288853Y137496D02*
Y134163D01*
G01Y138830D02*
X2288726Y138913D01*
Y139080D01*
X2288853Y139163D01*
X2288980Y139080D01*
Y138913D01*
X2288853Y138830D01*
G01X2295093Y134163D02*
Y137496D01*
G01Y136913D02*
X2294840Y137246D01*
X2294460Y137413D01*
X2294016Y137496D01*
X2293573Y137330D01*
X2293193Y136996D01*
X2292940Y136496D01*
X2292813Y135830D01*
X2292940Y135163D01*
X2293193Y134663D01*
X2293573Y134330D01*
X2294016Y134163D01*
X2294460Y134246D01*
X2294840Y134496D01*
X2295093Y134830D01*
G01X2297153Y134163D02*
Y137496D01*
G01Y136580D02*
X2297343Y136996D01*
X2297660Y137330D01*
X2298103Y137496D01*
X2298546Y137330D01*
X2298863Y136996D01*
X2299053Y136580D01*
Y134163D01*
G01Y136580D02*
X2299243Y136996D01*
X2299560Y137330D01*
X2300003Y137496D01*
X2300446Y137330D01*
X2300763Y136996D01*
X2300953Y136496D01*
Y134163D01*
G01X2303203Y136413D02*
X2305230D01*
X2305040Y136996D01*
X2304723Y137330D01*
X2304280Y137496D01*
X2303836Y137413D01*
X2303456Y137163D01*
X2303203Y136580D01*
X2303076Y136080D01*
Y135580D01*
X2303203Y135080D01*
X2303520Y134580D01*
X2303900Y134246D01*
X2304343Y134163D01*
X2304786Y134330D01*
X2305230Y134830D01*
G01X2309253Y139163D02*
Y134163D01*
G01X2308366Y137496D02*
X2310140D01*
G01X2313403Y136413D02*
X2315430D01*
X2315240Y136996D01*
X2314923Y137330D01*
X2314480Y137496D01*
X2314036Y137413D01*
X2313656Y137163D01*
X2313403Y136580D01*
X2313276Y136080D01*
Y135580D01*
X2313403Y135080D01*
X2313720Y134580D01*
X2314100Y134246D01*
X2314543Y134163D01*
X2314986Y134330D01*
X2315430Y134830D01*
G01X2318566Y134163D02*
Y137496D01*
G01Y136830D02*
X2318883Y137163D01*
X2319200Y137413D01*
X2319643Y137496D01*
X2319960Y137413D01*
X2320340Y137163D01*
G01X2328260Y135163D02*
X2328640Y134580D01*
X2329146Y134246D01*
X2329716Y134163D01*
X2330223Y134246D01*
X2330730Y134663D01*
X2331046Y135163D01*
X2331110Y135663D01*
X2330983Y136246D01*
X2330540Y136663D01*
X2330096Y136830D01*
X2329526D01*
G01X2330096D02*
X2330476Y137080D01*
X2330793Y137496D01*
X2330920Y137996D01*
X2330793Y138496D01*
X2330476Y138913D01*
X2329906Y139163D01*
X2329336Y139080D01*
X2328766Y138746D01*
G01X2332853Y134163D02*
Y137496D01*
G01Y136580D02*
X2333043Y136996D01*
X2333360Y137330D01*
X2333803Y137496D01*
X2334246Y137330D01*
X2334563Y136996D01*
X2334753Y136580D01*
Y134163D01*
G01Y136580D02*
X2334943Y136996D01*
X2335260Y137330D01*
X2335703Y137496D01*
X2336146Y137330D01*
X2336463Y136996D01*
X2336653Y136496D01*
Y134163D01*
G01X2337953D02*
Y137496D01*
G01Y136580D02*
X2338143Y136996D01*
X2338460Y137330D01*
X2338903Y137496D01*
X2339346Y137330D01*
X2339663Y136996D01*
X2339853Y136580D01*
Y134163D01*
G01Y136580D02*
X2340043Y136996D01*
X2340360Y137330D01*
X2340803Y137496D01*
X2341246Y137330D01*
X2341563Y136996D01*
X2341753Y136496D01*
Y134163D01*
G01X2348723Y134830D02*
X2349230Y134413D01*
X2349800Y134163D01*
X2350306D01*
X2350813Y134413D01*
X2351193Y134830D01*
X2351383Y135413D01*
X2351256Y135996D01*
X2350940Y136496D01*
X2350370Y136830D01*
X2349610Y136996D01*
X2349166Y137330D01*
X2348976Y137913D01*
X2349103Y138496D01*
X2349420Y138913D01*
X2349863Y139163D01*
X2350306D01*
X2350750Y138996D01*
X2351130Y138580D01*
G01X2355153Y134163D02*
X2354773Y134246D01*
X2354393Y134580D01*
X2354140Y135163D01*
X2354013Y135830D01*
X2354140Y136496D01*
X2354393Y137080D01*
X2354773Y137413D01*
X2355153Y137496D01*
X2355533Y137413D01*
X2355913Y137080D01*
X2356166Y136496D01*
X2356230Y135830D01*
X2356166Y135163D01*
X2355913Y134580D01*
X2355533Y134246D01*
X2355153Y134163D01*
G01X2360253D02*
Y139163D01*
G01X2366493D02*
Y134163D01*
G01Y134913D02*
X2366240Y134496D01*
X2365860Y134246D01*
X2365416Y134163D01*
X2364910Y134330D01*
X2364530Y134746D01*
X2364276Y135246D01*
X2364213Y135830D01*
X2364276Y136413D01*
X2364530Y136913D01*
X2364910Y137330D01*
X2365416Y137496D01*
X2365860Y137413D01*
X2366176Y137246D01*
X2366493Y136913D01*
G01X2369503Y136413D02*
X2371530D01*
X2371340Y136996D01*
X2371023Y137330D01*
X2370580Y137496D01*
X2370136Y137413D01*
X2369756Y137163D01*
X2369503Y136580D01*
X2369376Y136080D01*
Y135580D01*
X2369503Y135080D01*
X2369820Y134580D01*
X2370200Y134246D01*
X2370643Y134163D01*
X2371086Y134330D01*
X2371530Y134830D01*
G01X2374666Y134163D02*
Y137496D01*
G01Y136830D02*
X2374983Y137163D01*
X2375300Y137413D01*
X2375743Y137496D01*
X2376060Y137413D01*
X2376440Y137163D01*
G01X2378753Y134163D02*
Y137496D01*
G01Y136580D02*
X2378943Y136996D01*
X2379260Y137330D01*
X2379703Y137496D01*
X2380146Y137330D01*
X2380463Y136996D01*
X2380653Y136580D01*
Y134163D01*
G01Y136580D02*
X2380843Y136996D01*
X2381160Y137330D01*
X2381603Y137496D01*
X2382046Y137330D01*
X2382363Y136996D01*
X2382553Y136496D01*
Y134163D01*
G01X2386893D02*
Y137496D01*
G01Y136913D02*
X2386640Y137246D01*
X2386260Y137413D01*
X2385816Y137496D01*
X2385373Y137330D01*
X2384993Y136996D01*
X2384740Y136496D01*
X2384613Y135830D01*
X2384740Y135163D01*
X2384993Y134663D01*
X2385373Y134330D01*
X2385816Y134163D01*
X2386260Y134246D01*
X2386640Y134496D01*
X2386893Y134830D01*
G01X2389903Y134746D02*
X2390220Y134413D01*
X2390663Y134163D01*
X2391043D01*
X2391423Y134330D01*
X2391676Y134580D01*
X2391803Y134913D01*
X2391740Y135413D01*
X2391486Y135663D01*
X2390346Y136163D01*
X2390093Y136746D01*
X2390220Y137163D01*
X2390473Y137413D01*
X2390853Y137496D01*
X2391233Y137413D01*
X2391613Y137163D01*
G01X2394876Y134163D02*
Y139163D01*
G01X2396903Y137496D02*
X2394876Y135580D01*
G01X2395700Y136330D02*
X2397030Y134163D01*
G01X2206050Y146763D02*
Y151763D01*
X2208456D01*
G01X2207570Y149346D02*
X2206050D01*
G01X2212353Y150096D02*
Y146763D01*
G01Y151430D02*
X2212226Y151513D01*
Y151680D01*
X2212353Y151763D01*
X2212480Y151680D01*
Y151513D01*
X2212353Y151430D01*
G01X2218593Y151763D02*
Y146763D01*
G01Y147513D02*
X2218340Y147096D01*
X2217960Y146846D01*
X2217516Y146763D01*
X2217010Y146930D01*
X2216630Y147346D01*
X2216376Y147846D01*
X2216313Y148430D01*
X2216376Y149013D01*
X2216630Y149513D01*
X2217010Y149930D01*
X2217516Y150096D01*
X2217960Y150013D01*
X2218276Y149846D01*
X2218593Y149513D01*
G01X2221476Y150096D02*
Y147763D01*
X2221730Y147180D01*
X2222110Y146846D01*
X2222553Y146763D01*
X2222996Y146846D01*
X2223376Y147180D01*
X2223630Y147763D01*
G01Y146763D02*
Y150096D01*
G01X2228666Y149680D02*
X2228223Y150013D01*
X2227843Y150096D01*
X2227336Y149930D01*
X2226956Y149596D01*
X2226703Y149013D01*
X2226640Y148430D01*
X2226703Y147846D01*
X2226956Y147346D01*
X2227336Y146930D01*
X2227843Y146763D01*
X2228286Y146930D01*
X2228666Y147263D01*
G01X2232753Y150096D02*
Y146763D01*
G01Y151430D02*
X2232626Y151513D01*
Y151680D01*
X2232753Y151763D01*
X2232880Y151680D01*
Y151513D01*
X2232753Y151430D01*
G01X2238993Y146763D02*
Y150096D01*
G01Y149513D02*
X2238740Y149846D01*
X2238360Y150013D01*
X2237916Y150096D01*
X2237473Y149930D01*
X2237093Y149596D01*
X2236840Y149096D01*
X2236713Y148430D01*
X2236840Y147763D01*
X2237093Y147263D01*
X2237473Y146930D01*
X2237916Y146763D01*
X2238360Y146846D01*
X2238740Y147096D01*
X2238993Y147430D01*
G01X2242953Y146763D02*
Y151763D01*
G01X2251506Y146763D02*
Y151763D01*
X2253153Y147596D01*
X2254800Y151763D01*
Y146763D01*
G01X2259393D02*
Y150096D01*
G01Y149513D02*
X2259140Y149846D01*
X2258760Y150013D01*
X2258316Y150096D01*
X2257873Y149930D01*
X2257493Y149596D01*
X2257240Y149096D01*
X2257113Y148430D01*
X2257240Y147763D01*
X2257493Y147263D01*
X2257873Y146930D01*
X2258316Y146763D01*
X2258760Y146846D01*
X2259140Y147096D01*
X2259393Y147430D01*
G01X2262466Y146763D02*
Y150096D01*
G01Y149430D02*
X2262783Y149763D01*
X2263100Y150013D01*
X2263543Y150096D01*
X2263860Y150013D01*
X2264240Y149763D01*
G01X2267376Y146763D02*
Y151763D01*
G01X2269403Y150096D02*
X2267376Y148180D01*
G01X2268200Y148930D02*
X2269530Y146763D01*
G01X2273553Y146596D02*
X2273426Y146680D01*
Y146846D01*
X2273553Y146930D01*
X2273680Y146846D01*
Y146680D01*
X2273553Y146596D01*
G01Y148846D02*
X2273426Y148930D01*
Y149096D01*
X2273553Y149180D01*
X2273680Y149096D01*
Y148930D01*
X2273553Y148846D01*
G01X2282360Y146763D02*
Y151763D01*
X2283626D01*
X2284133Y151513D01*
X2284513Y151180D01*
X2284830Y150680D01*
X2285083Y150096D01*
X2285146Y149263D01*
X2285083Y148430D01*
X2284830Y147846D01*
X2284513Y147346D01*
X2284133Y147013D01*
X2283626Y146763D01*
X2282360D01*
G01X2288853Y150096D02*
Y146763D01*
G01Y151430D02*
X2288726Y151513D01*
Y151680D01*
X2288853Y151763D01*
X2288980Y151680D01*
Y151513D01*
X2288853Y151430D01*
G01X2295093Y146763D02*
Y150096D01*
G01Y149513D02*
X2294840Y149846D01*
X2294460Y150013D01*
X2294016Y150096D01*
X2293573Y149930D01*
X2293193Y149596D01*
X2292940Y149096D01*
X2292813Y148430D01*
X2292940Y147763D01*
X2293193Y147263D01*
X2293573Y146930D01*
X2294016Y146763D01*
X2294460Y146846D01*
X2294840Y147096D01*
X2295093Y147430D01*
G01X2297153Y146763D02*
Y150096D01*
G01Y149180D02*
X2297343Y149596D01*
X2297660Y149930D01*
X2298103Y150096D01*
X2298546Y149930D01*
X2298863Y149596D01*
X2299053Y149180D01*
Y146763D01*
G01Y149180D02*
X2299243Y149596D01*
X2299560Y149930D01*
X2300003Y150096D01*
X2300446Y149930D01*
X2300763Y149596D01*
X2300953Y149096D01*
Y146763D01*
G01X2303203Y149013D02*
X2305230D01*
X2305040Y149596D01*
X2304723Y149930D01*
X2304280Y150096D01*
X2303836Y150013D01*
X2303456Y149763D01*
X2303203Y149180D01*
X2303076Y148680D01*
Y148180D01*
X2303203Y147680D01*
X2303520Y147180D01*
X2303900Y146846D01*
X2304343Y146763D01*
X2304786Y146930D01*
X2305230Y147430D01*
G01X2309253Y151763D02*
Y146763D01*
G01X2308366Y150096D02*
X2310140D01*
G01X2313403Y149013D02*
X2315430D01*
X2315240Y149596D01*
X2314923Y149930D01*
X2314480Y150096D01*
X2314036Y150013D01*
X2313656Y149763D01*
X2313403Y149180D01*
X2313276Y148680D01*
Y148180D01*
X2313403Y147680D01*
X2313720Y147180D01*
X2314100Y146846D01*
X2314543Y146763D01*
X2314986Y146930D01*
X2315430Y147430D01*
G01X2318566Y146763D02*
Y150096D01*
G01Y149430D02*
X2318883Y149763D01*
X2319200Y150013D01*
X2319643Y150096D01*
X2319960Y150013D01*
X2320340Y149763D01*
G01X2329653Y146763D02*
Y151763D01*
X2328893Y150763D01*
G01Y146763D02*
X2330413D01*
G01X2332853D02*
Y150096D01*
G01Y149180D02*
X2333043Y149596D01*
X2333360Y149930D01*
X2333803Y150096D01*
X2334246Y149930D01*
X2334563Y149596D01*
X2334753Y149180D01*
Y146763D01*
G01Y149180D02*
X2334943Y149596D01*
X2335260Y149930D01*
X2335703Y150096D01*
X2336146Y149930D01*
X2336463Y149596D01*
X2336653Y149096D01*
Y146763D01*
G01X2337953D02*
Y150096D01*
G01Y149180D02*
X2338143Y149596D01*
X2338460Y149930D01*
X2338903Y150096D01*
X2339346Y149930D01*
X2339663Y149596D01*
X2339853Y149180D01*
Y146763D01*
G01Y149180D02*
X2340043Y149596D01*
X2340360Y149930D01*
X2340803Y150096D01*
X2341246Y149930D01*
X2341563Y149596D01*
X2341753Y149096D01*
Y146763D01*
G01X2351446Y151346D02*
X2351066Y151596D01*
X2350623Y151763D01*
X2350116D01*
X2349546Y151513D01*
X2349103Y151096D01*
X2348786Y150596D01*
X2348533Y149763D01*
X2348470Y149013D01*
X2348596Y148263D01*
X2348786Y147763D01*
X2349166Y147263D01*
X2349610Y146930D01*
X2350053Y146763D01*
X2350496D01*
X2350940Y146930D01*
X2351320Y147180D01*
X2351636Y147513D01*
G01X2355153Y146763D02*
X2354773Y146846D01*
X2354393Y147180D01*
X2354140Y147763D01*
X2354013Y148430D01*
X2354140Y149096D01*
X2354393Y149680D01*
X2354773Y150013D01*
X2355153Y150096D01*
X2355533Y150013D01*
X2355913Y149680D01*
X2356166Y149096D01*
X2356230Y148430D01*
X2356166Y147763D01*
X2355913Y147180D01*
X2355533Y146846D01*
X2355153Y146763D01*
G01X2359113Y145096D02*
Y150096D01*
G01Y149346D02*
X2359430Y149763D01*
X2359746Y150013D01*
X2360253Y150096D01*
X2360696Y150013D01*
X2361140Y149596D01*
X2361330Y149013D01*
X2361393Y148430D01*
X2361330Y147846D01*
X2361140Y147263D01*
X2360760Y146930D01*
X2360253Y146763D01*
X2359810Y146846D01*
X2359366Y147096D01*
X2359113Y147430D01*
G01X2364213Y145096D02*
Y150096D01*
G01Y149346D02*
X2364530Y149763D01*
X2364846Y150013D01*
X2365353Y150096D01*
X2365796Y150013D01*
X2366240Y149596D01*
X2366430Y149013D01*
X2366493Y148430D01*
X2366430Y147846D01*
X2366240Y147263D01*
X2365860Y146930D01*
X2365353Y146763D01*
X2364910Y146846D01*
X2364466Y147096D01*
X2364213Y147430D01*
G01X2369503Y149013D02*
X2371530D01*
X2371340Y149596D01*
X2371023Y149930D01*
X2370580Y150096D01*
X2370136Y150013D01*
X2369756Y149763D01*
X2369503Y149180D01*
X2369376Y148680D01*
Y148180D01*
X2369503Y147680D01*
X2369820Y147180D01*
X2370200Y146846D01*
X2370643Y146763D01*
X2371086Y146930D01*
X2371530Y147430D01*
G01X2374666Y146763D02*
Y150096D01*
G01Y149430D02*
X2374983Y149763D01*
X2375300Y150013D01*
X2375743Y150096D01*
X2376060Y150013D01*
X2376440Y149763D01*
G01X2279441Y208455D02*
Y203455D01*
G01X2277984Y208455D02*
X2280898D01*
G01X2284541Y203455D02*
X2284161Y203538D01*
X2283781Y203872D01*
X2283528Y204455D01*
X2283401Y205122D01*
X2283528Y205788D01*
X2283781Y206372D01*
X2284161Y206705D01*
X2284541Y206788D01*
X2284921Y206705D01*
X2285301Y206372D01*
X2285554Y205788D01*
X2285618Y205122D01*
X2285554Y204455D01*
X2285301Y203872D01*
X2284921Y203538D01*
X2284541Y203455D01*
G01X2289641D02*
Y208455D01*
G01X2293791Y205705D02*
X2295818D01*
X2295628Y206288D01*
X2295311Y206622D01*
X2294868Y206788D01*
X2294424Y206705D01*
X2294044Y206455D01*
X2293791Y205872D01*
X2293664Y205372D01*
Y204872D01*
X2293791Y204372D01*
X2294108Y203872D01*
X2294488Y203538D01*
X2294931Y203455D01*
X2295374Y203622D01*
X2295818Y204122D01*
G01X2298954Y203455D02*
Y206788D01*
G01Y206122D02*
X2299271Y206455D01*
X2299588Y206705D01*
X2300031Y206788D01*
X2300348Y206705D01*
X2300728Y206455D01*
G01X2306081Y203455D02*
Y206788D01*
G01Y206205D02*
X2305828Y206538D01*
X2305448Y206705D01*
X2305004Y206788D01*
X2304561Y206622D01*
X2304181Y206288D01*
X2303928Y205788D01*
X2303801Y205122D01*
X2303928Y204455D01*
X2304181Y203955D01*
X2304561Y203622D01*
X2305004Y203455D01*
X2305448Y203538D01*
X2305828Y203788D01*
X2306081Y204122D01*
G01X2308964Y203455D02*
Y206788D01*
G01Y205955D02*
X2309218Y206372D01*
X2309598Y206705D01*
X2310104Y206788D01*
X2310548Y206705D01*
X2310928Y206372D01*
X2311118Y205788D01*
Y203455D01*
G01X2316154Y206372D02*
X2315711Y206705D01*
X2315331Y206788D01*
X2314824Y206622D01*
X2314444Y206288D01*
X2314191Y205705D01*
X2314128Y205122D01*
X2314191Y204538D01*
X2314444Y204038D01*
X2314824Y203622D01*
X2315331Y203455D01*
X2315774Y203622D01*
X2316154Y203955D01*
G01X2319291Y205705D02*
X2321318D01*
X2321128Y206288D01*
X2320811Y206622D01*
X2320368Y206788D01*
X2319924Y206705D01*
X2319544Y206455D01*
X2319291Y205872D01*
X2319164Y205372D01*
Y204872D01*
X2319291Y204372D01*
X2319608Y203872D01*
X2319988Y203538D01*
X2320431Y203455D01*
X2320874Y203622D01*
X2321318Y204122D01*
G01X2329744Y205122D02*
X2331264D01*
G01X2330441Y206205D02*
Y204038D01*
G01X2335541Y208455D02*
X2335034Y208288D01*
X2334654Y207872D01*
X2334401Y207372D01*
X2334211Y206705D01*
X2334148Y205955D01*
X2334211Y205205D01*
X2334401Y204538D01*
X2334654Y204038D01*
X2335034Y203622D01*
X2335541Y203455D01*
X2336048Y203622D01*
X2336428Y204038D01*
X2336681Y204538D01*
X2336871Y205205D01*
X2336934Y205955D01*
X2336871Y206705D01*
X2336681Y207372D01*
X2336428Y207872D01*
X2336048Y208288D01*
X2335541Y208455D01*
G01X2340641Y203288D02*
X2340514Y203372D01*
Y203538D01*
X2340641Y203622D01*
X2340768Y203538D01*
Y203372D01*
X2340641Y203288D01*
G01X2345741Y208455D02*
X2345234Y208288D01*
X2344854Y207872D01*
X2344601Y207372D01*
X2344411Y206705D01*
X2344348Y205955D01*
X2344411Y205205D01*
X2344601Y204538D01*
X2344854Y204038D01*
X2345234Y203622D01*
X2345741Y203455D01*
X2346248Y203622D01*
X2346628Y204038D01*
X2346881Y204538D01*
X2347071Y205205D01*
X2347134Y205955D01*
X2347071Y206705D01*
X2346881Y207372D01*
X2346628Y207872D01*
X2346248Y208288D01*
X2345741Y208455D01*
G01X2349448Y204205D02*
X2349828Y203788D01*
X2350271Y203538D01*
X2350841Y203455D01*
X2351411Y203622D01*
X2351854Y203955D01*
X2352171Y204538D01*
X2352234Y205205D01*
X2352108Y205872D01*
X2351791Y206288D01*
X2351348Y206622D01*
X2350904Y206705D01*
X2350461Y206622D01*
X2349891Y206288D01*
X2350081Y208455D01*
X2351791D01*
G01X2355941D02*
X2355434Y208288D01*
X2355054Y207872D01*
X2354801Y207372D01*
X2354611Y206705D01*
X2354548Y205955D01*
X2354611Y205205D01*
X2354801Y204538D01*
X2355054Y204038D01*
X2355434Y203622D01*
X2355941Y203455D01*
X2356448Y203622D01*
X2356828Y204038D01*
X2357081Y204538D01*
X2357271Y205205D01*
X2357334Y205955D01*
X2357271Y206705D01*
X2357081Y207372D01*
X2356828Y207872D01*
X2356448Y208288D01*
X2355941Y208455D01*
G01X2361041Y203455D02*
X2361484Y203538D01*
X2361991Y203788D01*
X2362308Y204205D01*
X2362434Y204788D01*
X2362308Y205372D01*
X2361928Y205872D01*
X2361358Y206122D01*
X2360724D01*
X2360344Y206288D01*
X2360028Y206705D01*
X2359901Y207288D01*
X2360091Y207872D01*
X2360534Y208288D01*
X2361041Y208455D01*
X2361548Y208288D01*
X2361991Y207872D01*
X2362181Y207288D01*
X2362054Y206705D01*
X2361738Y206288D01*
X2361358Y206122D01*
X2360724D01*
X2360154Y205872D01*
X2359774Y205372D01*
X2359648Y204788D01*
X2359774Y204205D01*
X2360091Y203788D01*
X2360598Y203538D01*
X2361041Y203455D01*
G01X2364241D02*
Y206788D01*
G01Y205872D02*
X2364431Y206288D01*
X2364748Y206622D01*
X2365191Y206788D01*
X2365634Y206622D01*
X2365951Y206288D01*
X2366141Y205872D01*
Y203455D01*
G01Y205872D02*
X2366331Y206288D01*
X2366648Y206622D01*
X2367091Y206788D01*
X2367534Y206622D01*
X2367851Y206288D01*
X2368041Y205788D01*
Y203455D01*
G01X2369341D02*
Y206788D01*
G01Y205872D02*
X2369531Y206288D01*
X2369848Y206622D01*
X2370291Y206788D01*
X2370734Y206622D01*
X2371051Y206288D01*
X2371241Y205872D01*
Y203455D01*
G01Y205872D02*
X2371431Y206288D01*
X2371748Y206622D01*
X2372191Y206788D01*
X2372634Y206622D01*
X2372951Y206288D01*
X2373141Y205788D01*
Y203455D01*
G01X2375201Y203288D02*
X2377481Y208455D01*
G01X2380618Y205122D02*
X2382264D01*
G01X2386541Y208455D02*
X2386034Y208288D01*
X2385654Y207872D01*
X2385401Y207372D01*
X2385211Y206705D01*
X2385148Y205955D01*
X2385211Y205205D01*
X2385401Y204538D01*
X2385654Y204038D01*
X2386034Y203622D01*
X2386541Y203455D01*
X2387048Y203622D01*
X2387428Y204038D01*
X2387681Y204538D01*
X2387871Y205205D01*
X2387934Y205955D01*
X2387871Y206705D01*
X2387681Y207372D01*
X2387428Y207872D01*
X2387048Y208288D01*
X2386541Y208455D01*
G01X2391641Y203288D02*
X2391514Y203372D01*
Y203538D01*
X2391641Y203622D01*
X2391768Y203538D01*
Y203372D01*
X2391641Y203288D01*
G01X2396741Y208455D02*
X2396234Y208288D01*
X2395854Y207872D01*
X2395601Y207372D01*
X2395411Y206705D01*
X2395348Y205955D01*
X2395411Y205205D01*
X2395601Y204538D01*
X2395854Y204038D01*
X2396234Y203622D01*
X2396741Y203455D01*
X2397248Y203622D01*
X2397628Y204038D01*
X2397881Y204538D01*
X2398071Y205205D01*
X2398134Y205955D01*
X2398071Y206705D01*
X2397881Y207372D01*
X2397628Y207872D01*
X2397248Y208288D01*
X2396741Y208455D01*
G01X2401841D02*
X2401334Y208288D01*
X2400954Y207872D01*
X2400701Y207372D01*
X2400511Y206705D01*
X2400448Y205955D01*
X2400511Y205205D01*
X2400701Y204538D01*
X2400954Y204038D01*
X2401334Y203622D01*
X2401841Y203455D01*
X2402348Y203622D01*
X2402728Y204038D01*
X2402981Y204538D01*
X2403171Y205205D01*
X2403234Y205955D01*
X2403171Y206705D01*
X2402981Y207372D01*
X2402728Y207872D01*
X2402348Y208288D01*
X2401841Y208455D01*
G01X2406941D02*
X2406434Y208288D01*
X2406054Y207872D01*
X2405801Y207372D01*
X2405611Y206705D01*
X2405548Y205955D01*
X2405611Y205205D01*
X2405801Y204538D01*
X2406054Y204038D01*
X2406434Y203622D01*
X2406941Y203455D01*
X2407448Y203622D01*
X2407828Y204038D01*
X2408081Y204538D01*
X2408271Y205205D01*
X2408334Y205955D01*
X2408271Y206705D01*
X2408081Y207372D01*
X2407828Y207872D01*
X2407448Y208288D01*
X2406941Y208455D01*
G01X2412041D02*
X2411534Y208288D01*
X2411154Y207872D01*
X2410901Y207372D01*
X2410711Y206705D01*
X2410648Y205955D01*
X2410711Y205205D01*
X2410901Y204538D01*
X2411154Y204038D01*
X2411534Y203622D01*
X2412041Y203455D01*
X2412548Y203622D01*
X2412928Y204038D01*
X2413181Y204538D01*
X2413371Y205205D01*
X2413434Y205955D01*
X2413371Y206705D01*
X2413181Y207372D01*
X2412928Y207872D01*
X2412548Y208288D01*
X2412041Y208455D01*
G01X2415241Y203455D02*
Y206788D01*
G01Y205872D02*
X2415431Y206288D01*
X2415748Y206622D01*
X2416191Y206788D01*
X2416634Y206622D01*
X2416951Y206288D01*
X2417141Y205872D01*
Y203455D01*
G01Y205872D02*
X2417331Y206288D01*
X2417648Y206622D01*
X2418091Y206788D01*
X2418534Y206622D01*
X2418851Y206288D01*
X2419041Y205788D01*
Y203455D01*
G01X2420341D02*
Y206788D01*
G01Y205872D02*
X2420531Y206288D01*
X2420848Y206622D01*
X2421291Y206788D01*
X2421734Y206622D01*
X2422051Y206288D01*
X2422241Y205872D01*
Y203455D01*
G01Y205872D02*
X2422431Y206288D01*
X2422748Y206622D01*
X2423191Y206788D01*
X2423634Y206622D01*
X2423951Y206288D01*
X2424141Y205788D01*
Y203455D01*
G01X2208041Y221055D02*
Y216055D01*
G01X2206584Y221055D02*
X2209498D01*
G01X2213141Y216055D02*
X2212761Y216138D01*
X2212381Y216472D01*
X2212128Y217055D01*
X2212001Y217722D01*
X2212128Y218388D01*
X2212381Y218972D01*
X2212761Y219305D01*
X2213141Y219388D01*
X2213521Y219305D01*
X2213901Y218972D01*
X2214154Y218388D01*
X2214218Y217722D01*
X2214154Y217055D01*
X2213901Y216472D01*
X2213521Y216138D01*
X2213141Y216055D01*
G01X2218241D02*
X2217861Y216138D01*
X2217481Y216472D01*
X2217228Y217055D01*
X2217101Y217722D01*
X2217228Y218388D01*
X2217481Y218972D01*
X2217861Y219305D01*
X2218241Y219388D01*
X2218621Y219305D01*
X2219001Y218972D01*
X2219254Y218388D01*
X2219318Y217722D01*
X2219254Y217055D01*
X2219001Y216472D01*
X2218621Y216138D01*
X2218241Y216055D01*
G01X2223341D02*
Y221055D01*
G01X2228441Y219388D02*
Y216055D01*
G01Y220722D02*
X2228314Y220805D01*
Y220972D01*
X2228441Y221055D01*
X2228568Y220972D01*
Y220805D01*
X2228441Y220722D01*
G01X2232464Y216055D02*
Y219388D01*
G01Y218555D02*
X2232718Y218972D01*
X2233098Y219305D01*
X2233604Y219388D01*
X2234048Y219305D01*
X2234428Y218972D01*
X2234618Y218388D01*
Y216055D01*
G01X2237754Y214805D02*
X2238198Y214472D01*
X2238704Y214388D01*
X2239148Y214472D01*
X2239528Y214888D01*
X2239781Y215472D01*
Y219388D01*
G01Y218722D02*
X2239528Y219055D01*
X2239148Y219305D01*
X2238704Y219388D01*
X2238198Y219222D01*
X2237881Y218888D01*
X2237628Y218305D01*
X2237501Y217722D01*
X2237564Y217222D01*
X2237818Y216638D01*
X2238198Y216222D01*
X2238704Y216055D01*
X2239084Y216138D01*
X2239528Y216472D01*
X2239781Y216805D01*
G01X2247511Y216055D02*
Y221055D01*
G01X2250171D02*
Y216055D01*
G01Y218555D02*
X2247511D01*
G01X2253941Y216055D02*
X2253561Y216138D01*
X2253181Y216472D01*
X2252928Y217055D01*
X2252801Y217722D01*
X2252928Y218388D01*
X2253181Y218972D01*
X2253561Y219305D01*
X2253941Y219388D01*
X2254321Y219305D01*
X2254701Y218972D01*
X2254954Y218388D01*
X2255018Y217722D01*
X2254954Y217055D01*
X2254701Y216472D01*
X2254321Y216138D01*
X2253941Y216055D01*
G01X2259041D02*
Y221055D01*
G01X2263191Y218305D02*
X2265218D01*
X2265028Y218888D01*
X2264711Y219222D01*
X2264268Y219388D01*
X2263824Y219305D01*
X2263444Y219055D01*
X2263191Y218472D01*
X2263064Y217972D01*
Y217472D01*
X2263191Y216972D01*
X2263508Y216472D01*
X2263888Y216138D01*
X2264331Y216055D01*
X2264774Y216222D01*
X2265218Y216722D01*
G01X2269241Y215888D02*
X2269114Y215972D01*
Y216138D01*
X2269241Y216222D01*
X2269368Y216138D01*
Y215972D01*
X2269241Y215888D01*
G01Y218138D02*
X2269114Y218222D01*
Y218388D01*
X2269241Y218472D01*
X2269368Y218388D01*
Y218222D01*
X2269241Y218138D01*
G01X2278048Y216055D02*
Y221055D01*
X2279314D01*
X2279821Y220805D01*
X2280201Y220472D01*
X2280518Y219972D01*
X2280771Y219388D01*
X2280834Y218555D01*
X2280771Y217722D01*
X2280518Y217138D01*
X2280201Y216638D01*
X2279821Y216305D01*
X2279314Y216055D01*
X2278048D01*
G01X2284541Y219388D02*
Y216055D01*
G01Y220722D02*
X2284414Y220805D01*
Y220972D01*
X2284541Y221055D01*
X2284668Y220972D01*
Y220805D01*
X2284541Y220722D01*
G01X2290781Y216055D02*
Y219388D01*
G01Y218805D02*
X2290528Y219138D01*
X2290148Y219305D01*
X2289704Y219388D01*
X2289261Y219222D01*
X2288881Y218888D01*
X2288628Y218388D01*
X2288501Y217722D01*
X2288628Y217055D01*
X2288881Y216555D01*
X2289261Y216222D01*
X2289704Y216055D01*
X2290148Y216138D01*
X2290528Y216388D01*
X2290781Y216722D01*
G01X2292841Y216055D02*
Y219388D01*
G01Y218472D02*
X2293031Y218888D01*
X2293348Y219222D01*
X2293791Y219388D01*
X2294234Y219222D01*
X2294551Y218888D01*
X2294741Y218472D01*
Y216055D01*
G01Y218472D02*
X2294931Y218888D01*
X2295248Y219222D01*
X2295691Y219388D01*
X2296134Y219222D01*
X2296451Y218888D01*
X2296641Y218388D01*
Y216055D01*
G01X2298891Y218305D02*
X2300918D01*
X2300728Y218888D01*
X2300411Y219222D01*
X2299968Y219388D01*
X2299524Y219305D01*
X2299144Y219055D01*
X2298891Y218472D01*
X2298764Y217972D01*
Y217472D01*
X2298891Y216972D01*
X2299208Y216472D01*
X2299588Y216138D01*
X2300031Y216055D01*
X2300474Y216222D01*
X2300918Y216722D01*
G01X2304941Y221055D02*
Y216055D01*
G01X2304054Y219388D02*
X2305828D01*
G01X2309091Y218305D02*
X2311118D01*
X2310928Y218888D01*
X2310611Y219222D01*
X2310168Y219388D01*
X2309724Y219305D01*
X2309344Y219055D01*
X2309091Y218472D01*
X2308964Y217972D01*
Y217472D01*
X2309091Y216972D01*
X2309408Y216472D01*
X2309788Y216138D01*
X2310231Y216055D01*
X2310674Y216222D01*
X2311118Y216722D01*
G01X2314254Y216055D02*
Y219388D01*
G01Y218722D02*
X2314571Y219055D01*
X2314888Y219305D01*
X2315331Y219388D01*
X2315648Y219305D01*
X2316028Y219055D01*
G01X2323948Y217055D02*
X2324328Y216472D01*
X2324834Y216138D01*
X2325404Y216055D01*
X2325911Y216138D01*
X2326418Y216555D01*
X2326734Y217055D01*
X2326798Y217555D01*
X2326671Y218138D01*
X2326228Y218555D01*
X2325784Y218722D01*
X2325214D01*
G01X2325784D02*
X2326164Y218972D01*
X2326481Y219388D01*
X2326608Y219888D01*
X2326481Y220388D01*
X2326164Y220805D01*
X2325594Y221055D01*
X2325024Y220972D01*
X2324454Y220638D01*
G01X2330441Y215888D02*
X2330314Y215972D01*
Y216138D01*
X2330441Y216222D01*
X2330568Y216138D01*
Y215972D01*
X2330441Y215888D01*
G01X2335541Y216055D02*
Y221055D01*
X2334781Y220055D01*
G01Y216055D02*
X2336301D01*
G01X2340514D02*
X2340641Y217138D01*
X2340831Y218055D01*
X2341084Y218888D01*
X2341401Y219805D01*
X2341908Y221055D01*
X2339374D01*
G01X2344348Y216805D02*
X2344728Y216388D01*
X2345171Y216138D01*
X2345741Y216055D01*
X2346311Y216222D01*
X2346754Y216555D01*
X2347071Y217138D01*
X2347134Y217805D01*
X2347008Y218472D01*
X2346691Y218888D01*
X2346248Y219222D01*
X2345804Y219305D01*
X2345361Y219222D01*
X2344791Y218888D01*
X2344981Y221055D01*
X2346691D01*
G01X2348941Y216055D02*
Y219388D01*
G01Y218472D02*
X2349131Y218888D01*
X2349448Y219222D01*
X2349891Y219388D01*
X2350334Y219222D01*
X2350651Y218888D01*
X2350841Y218472D01*
Y216055D01*
G01Y218472D02*
X2351031Y218888D01*
X2351348Y219222D01*
X2351791Y219388D01*
X2352234Y219222D01*
X2352551Y218888D01*
X2352741Y218388D01*
Y216055D01*
G01X2354041D02*
Y219388D01*
G01Y218472D02*
X2354231Y218888D01*
X2354548Y219222D01*
X2354991Y219388D01*
X2355434Y219222D01*
X2355751Y218888D01*
X2355941Y218472D01*
Y216055D01*
G01Y218472D02*
X2356131Y218888D01*
X2356448Y219222D01*
X2356891Y219388D01*
X2357334Y219222D01*
X2357651Y218888D01*
X2357841Y218388D01*
Y216055D01*
G01X2364684D02*
Y221055D01*
X2367598Y216055D01*
Y221055D01*
G01X2369974Y216055D02*
Y221055D01*
X2371494D01*
X2372001Y220805D01*
X2372381Y220222D01*
X2372508Y219555D01*
X2372381Y218888D01*
X2372064Y218388D01*
X2371494Y218138D01*
X2369974D01*
G01X2376341Y221055D02*
Y216055D01*
G01X2374884Y221055D02*
X2377798D01*
G01X2380111Y216055D02*
Y221055D01*
G01X2382771D02*
Y216055D01*
G01Y218555D02*
X2380111D01*
G01X2226797Y5403D02*
X2226297Y5783D01*
X2226047Y6226D01*
X2225964Y6733D01*
X2226131Y7366D01*
X2226547Y7809D01*
X2227047Y7936D01*
X2227547Y7873D01*
X2227964Y7619D01*
X2228797Y6353D01*
X2229381Y5783D01*
X2230214Y5403D01*
X2230964Y5276D01*
Y7936D01*
G01X2234448Y-3237D02*
X2233464Y2669D01*
X2232479Y-3237D01*
X2234448D01*
G01X2248031Y10543D02*
X2233070D01*
G01X2248031Y2669D02*
X2233070D01*
G01X2233464Y6606D02*
Y2669D01*
G01Y6606D02*
Y10543D01*
G01X2232479Y16448D02*
X2233464Y10543D01*
X2234448Y16448D01*
X2232479D01*
G01X2251487Y73884D02*
X2242477Y74149D01*
G01X2235294Y83283D02*
X2248757Y61742D01*
G01X2239259Y78797D02*
X2235294Y83283D01*
X2237590Y77754D01*
X2239259Y78797D01*
G01X2246376Y88125D02*
X2240843Y85838D01*
X2246819Y86207D01*
X2246376Y88125D01*
G01X2240843Y85838D02*
X2271172Y92837D01*
G01X2246143Y185863D02*
X2240589Y183625D01*
X2246568Y183941D01*
X2246143Y185863D01*
G01X2240589Y183625D02*
X2284692Y193390D01*
G01X2256692Y-16032D02*
X2262597Y-15048D01*
X2256692Y-14063D01*
Y-16032D01*
G01X2247883Y67858D02*
X2252123Y70508D01*
X2250872Y70622D01*
G01X2247480Y68502D02*
X2248286Y67213D01*
G01X2249482Y74017D02*
G03I-2500J0D01*
G01X2261489Y95156D02*
G03I-2501J0D01*
G01X2260581Y99372D02*
X2257396Y90941D01*
G01X2257141Y190875D02*
X2257638Y190387D01*
X2258204Y190172D01*
X2258779Y190213D01*
X2259256Y190404D01*
X2259660Y190921D01*
X2259861Y191477D01*
X2259815Y191979D01*
X2259565Y192521D01*
X2259042Y192832D01*
X2258573Y192899D01*
X2258017Y192776D01*
G01X2258573Y192899D02*
X2258890Y193225D01*
X2259110Y193701D01*
X2259125Y194216D01*
X2258893Y194677D01*
X2258494Y195015D01*
X2257884Y195136D01*
X2257345Y194932D01*
X2256861Y194483D01*
G01X2263732Y191139D02*
X2263590Y191193D01*
X2263554Y191356D01*
X2263660Y191464D01*
X2263802Y191410D01*
X2263838Y191248D01*
X2263732Y191139D01*
G01X2268675Y192404D02*
X2267594Y197285D01*
X2267068Y196145D01*
G01X2267933Y192239D02*
X2269417Y192568D01*
G01X2273530Y193478D02*
X2273420Y194563D01*
X2273407Y195499D01*
X2273474Y196368D01*
X2273586Y197331D01*
X2273810Y198661D01*
X2271337Y198114D01*
G01X2277111Y195039D02*
X2277572Y194714D01*
X2278058Y194566D01*
X2278633Y194608D01*
X2279154Y194894D01*
X2279514Y195315D01*
X2279697Y195953D01*
X2279615Y196617D01*
X2279347Y197241D01*
X2278948Y197579D01*
X2278443Y197809D01*
X2277992Y197794D01*
X2277578Y197617D01*
X2277093Y197169D01*
X2276810Y199325D01*
X2278480Y199695D01*
G01X2255111Y191408D02*
G03I-2500J0D01*
G01X2254242Y195610D02*
X2250981Y187207D01*
G01X2267504Y-11548D02*
X2267884Y-12131D01*
X2268390Y-12465D01*
X2268960Y-12548D01*
X2269467Y-12465D01*
X2269974Y-12048D01*
X2270290Y-11548D01*
X2270354Y-11048D01*
X2270227Y-10465D01*
X2269784Y-10048D01*
X2269340Y-9881D01*
X2268770D01*
G01X2269340D02*
X2269720Y-9631D01*
X2270037Y-9215D01*
X2270164Y-8715D01*
X2270037Y-8215D01*
X2269720Y-7798D01*
X2269150Y-7548D01*
X2268580Y-7631D01*
X2268010Y-7965D01*
G01X2262597Y4244D02*
Y-15441D01*
G01X2268897Y-15048D02*
X2262597D01*
G01X2268897D02*
X2274408D01*
G01X2263522Y94663D02*
X2264023Y94180D01*
X2264592Y93969D01*
X2265166Y94016D01*
X2265641Y94212D01*
X2266041Y94731D01*
X2266237Y95290D01*
X2266186Y95791D01*
X2265932Y96331D01*
X2265406Y96637D01*
X2264937Y96700D01*
X2264381Y96572D01*
G01X2264937Y96700D02*
X2265251Y97029D01*
X2265466Y97506D01*
X2265477Y98022D01*
X2265241Y98481D01*
X2264839Y98816D01*
X2264227Y98931D01*
X2263690Y98722D01*
X2263210Y98269D01*
G01X2274408Y4244D02*
Y-15441D01*
G01X2280314Y-14063D02*
X2274408Y-15048D01*
X2280314Y-16032D01*
Y-14063D01*
G01X2382915Y-59536D02*
Y-54536D01*
X2384435D01*
X2384942Y-54786D01*
X2385322Y-55369D01*
X2385449Y-56036D01*
X2385322Y-56703D01*
X2385005Y-57203D01*
X2384435Y-57453D01*
X2382915D01*
G01X2390422Y-59536D02*
Y-56203D01*
G01Y-56786D02*
X2390169Y-56453D01*
X2389789Y-56286D01*
X2389345Y-56203D01*
X2388902Y-56369D01*
X2388522Y-56703D01*
X2388269Y-57203D01*
X2388142Y-57869D01*
X2388269Y-58536D01*
X2388522Y-59036D01*
X2388902Y-59369D01*
X2389345Y-59536D01*
X2389789Y-59453D01*
X2390169Y-59203D01*
X2390422Y-58869D01*
G01X2393305Y-59536D02*
Y-56203D01*
G01Y-57036D02*
X2393559Y-56619D01*
X2393939Y-56286D01*
X2394445Y-56203D01*
X2394889Y-56286D01*
X2395269Y-56619D01*
X2395459Y-57203D01*
Y-59536D01*
G01X2398532Y-57286D02*
X2400559D01*
X2400369Y-56703D01*
X2400052Y-56369D01*
X2399609Y-56203D01*
X2399165Y-56286D01*
X2398785Y-56536D01*
X2398532Y-57119D01*
X2398405Y-57619D01*
Y-58119D01*
X2398532Y-58619D01*
X2398849Y-59119D01*
X2399229Y-59453D01*
X2399672Y-59536D01*
X2400115Y-59369D01*
X2400559Y-58869D01*
G01X2404582Y-59536D02*
Y-54536D01*
G01X2413515Y-59536D02*
Y-54536D01*
X2415099D01*
X2415605Y-54786D01*
X2415922Y-55119D01*
X2416049Y-55786D01*
X2415922Y-56453D01*
X2415542Y-56869D01*
X2415099Y-57119D01*
X2413515D01*
G01X2415099D02*
X2416049Y-59536D01*
G01X2418932Y-57286D02*
X2420959D01*
X2420769Y-56703D01*
X2420452Y-56369D01*
X2420009Y-56203D01*
X2419565Y-56286D01*
X2419185Y-56536D01*
X2418932Y-57119D01*
X2418805Y-57619D01*
Y-58119D01*
X2418932Y-58619D01*
X2419249Y-59119D01*
X2419629Y-59453D01*
X2420072Y-59536D01*
X2420515Y-59369D01*
X2420959Y-58869D01*
G01X2423842Y-56203D02*
X2424982Y-59536D01*
X2426122Y-56203D01*
G01X2435689Y-56869D02*
X2435942Y-56619D01*
X2436132Y-56203D01*
X2436259Y-55619D01*
X2436132Y-55119D01*
X2435879Y-54786D01*
X2435435Y-54536D01*
X2433725D01*
Y-59536D01*
X2435815D01*
X2436259Y-59203D01*
X2436512Y-58703D01*
X2436639Y-58119D01*
X2436512Y-57536D01*
X2436132Y-57036D01*
X2435689Y-56869D01*
X2433725D01*
G01X-476840Y-884638D02*
Y2768362D01*
X5911000D01*
Y-884638D01*
X-476840D01*
G01X8820Y-607488D02*
X10387D01*
Y-609378D01*
X9917Y-610008D01*
X9368Y-610428D01*
X8585Y-610638D01*
X7802Y-610428D01*
X7253Y-610008D01*
X6783Y-609378D01*
X6470Y-608643D01*
X6313Y-607803D01*
Y-607068D01*
X6470Y-606438D01*
X6783Y-605703D01*
X7253Y-605073D01*
X7723Y-604653D01*
X8350Y-604338D01*
X8898D01*
X9525Y-604548D01*
X9995Y-604968D01*
G01X12927Y-604338D02*
Y-608853D01*
X13240Y-609798D01*
X13867Y-610428D01*
X14650Y-610638D01*
X15433Y-610428D01*
X16060Y-609798D01*
X16373Y-608853D01*
Y-604338D01*
G01X20010D02*
X21890D01*
G01X20950D02*
Y-610638D01*
G01X20010D02*
X21890D01*
G01X25605Y-609798D02*
X26232Y-610323D01*
X26937Y-610638D01*
X27563D01*
X28190Y-610323D01*
X28660Y-609798D01*
X28895Y-609063D01*
X28738Y-608328D01*
X28347Y-607698D01*
X27642Y-607278D01*
X26702Y-607068D01*
X26153Y-606648D01*
X25918Y-605913D01*
X26075Y-605178D01*
X26467Y-604653D01*
X27015Y-604338D01*
X27563D01*
X28112Y-604548D01*
X28582Y-605073D01*
G01X31905Y-610638D02*
Y-604338D01*
G01X35195D02*
Y-610638D01*
G01Y-607488D02*
X31905D01*
G01X37892Y-610638D02*
X39850Y-604338D01*
X41808Y-610638D01*
G01X41103Y-608433D02*
X38597D01*
G01X44348Y-610638D02*
Y-604338D01*
X47952Y-610638D01*
Y-604338D01*
G01X57027Y-610638D02*
Y-604338D01*
X58593D01*
X59220Y-604653D01*
X59690Y-605073D01*
X60082Y-605703D01*
X60395Y-606438D01*
X60473Y-607488D01*
X60395Y-608538D01*
X60082Y-609273D01*
X59690Y-609903D01*
X59220Y-610323D01*
X58593Y-610638D01*
X57027D01*
G01X64110Y-604338D02*
X65990D01*
G01X65050D02*
Y-610638D01*
G01X64110D02*
X65990D01*
G01X69705Y-609798D02*
X70332Y-610323D01*
X71037Y-610638D01*
X71663D01*
X72290Y-610323D01*
X72760Y-609798D01*
X72995Y-609063D01*
X72838Y-608328D01*
X72447Y-607698D01*
X71742Y-607278D01*
X70802Y-607068D01*
X70253Y-606648D01*
X70018Y-605913D01*
X70175Y-605178D01*
X70567Y-604653D01*
X71115Y-604338D01*
X71663D01*
X72212Y-604548D01*
X72682Y-605073D01*
G01X77650Y-604338D02*
Y-610638D01*
G01X75848Y-604338D02*
X79452D01*
G01X83950Y-610848D02*
X83793Y-610743D01*
Y-610533D01*
X83950Y-610428D01*
X84107Y-610533D01*
Y-610743D01*
X83950Y-610848D01*
G01X90093Y-611793D02*
X90407Y-610428D01*
G01X96550Y-604338D02*
Y-610638D01*
G01X94748Y-604338D02*
X98352D01*
G01X100892Y-610638D02*
X102850Y-604338D01*
X104808Y-610638D01*
G01X104103Y-608433D02*
X101597D01*
G01X109150Y-610638D02*
X108523Y-610533D01*
X107975Y-610113D01*
X107505Y-609483D01*
X107192Y-608748D01*
X107035Y-607908D01*
Y-607068D01*
X107192Y-606228D01*
X107505Y-605493D01*
X107975Y-604863D01*
X108523Y-604443D01*
X109150Y-604338D01*
X109777Y-604443D01*
X110325Y-604863D01*
X110795Y-605493D01*
X111108Y-606228D01*
X111265Y-607068D01*
Y-607908D01*
X111108Y-608748D01*
X110795Y-609483D01*
X110325Y-610113D01*
X109777Y-610533D01*
X109150Y-610638D01*
G01X115450D02*
Y-607803D01*
X113883Y-604338D01*
G01X117017D02*
X115450Y-607803D01*
G01X120027Y-604338D02*
Y-608853D01*
X120340Y-609798D01*
X120967Y-610428D01*
X121750Y-610638D01*
X122533Y-610428D01*
X123160Y-609798D01*
X123473Y-608853D01*
Y-604338D01*
G01X126092Y-610638D02*
X128050Y-604338D01*
X130008Y-610638D01*
G01X129303Y-608433D02*
X126797D01*
G01X132548Y-610638D02*
Y-604338D01*
X136152Y-610638D01*
Y-604338D01*
G01X10073Y-614863D02*
X9603Y-614548D01*
X9055Y-614338D01*
X8428D01*
X7723Y-614653D01*
X7175Y-615178D01*
X6783Y-615808D01*
X6470Y-616858D01*
X6392Y-617803D01*
X6548Y-618748D01*
X6783Y-619378D01*
X7253Y-620008D01*
X7802Y-620428D01*
X8350Y-620638D01*
X8898D01*
X9447Y-620428D01*
X9917Y-620113D01*
X10308Y-619693D01*
G01X13710Y-614338D02*
X15590D01*
G01X14650D02*
Y-620638D01*
G01X13710D02*
X15590D01*
G01X20950Y-614338D02*
Y-620638D01*
G01X19148Y-614338D02*
X22752D01*
G01X27250Y-620638D02*
Y-617803D01*
X25683Y-614338D01*
G01X28817D02*
X27250Y-617803D01*
G01X38127Y-619378D02*
X38597Y-620113D01*
X39223Y-620533D01*
X39928Y-620638D01*
X40555Y-620533D01*
X41182Y-620008D01*
X41573Y-619378D01*
X41652Y-618748D01*
X41495Y-618013D01*
X40947Y-617488D01*
X40398Y-617278D01*
X39693D01*
G01X40398D02*
X40868Y-616963D01*
X41260Y-616438D01*
X41417Y-615808D01*
X41260Y-615178D01*
X40868Y-614653D01*
X40163Y-614338D01*
X39458Y-614443D01*
X38753Y-614863D01*
G01X44427Y-619378D02*
X44897Y-620113D01*
X45523Y-620533D01*
X46228Y-620638D01*
X46855Y-620533D01*
X47482Y-620008D01*
X47873Y-619378D01*
X47952Y-618748D01*
X47795Y-618013D01*
X47247Y-617488D01*
X46698Y-617278D01*
X45993D01*
G01X46698D02*
X47168Y-616963D01*
X47560Y-616438D01*
X47717Y-615808D01*
X47560Y-615178D01*
X47168Y-614653D01*
X46463Y-614338D01*
X45758Y-614443D01*
X45053Y-614863D01*
G01X50727Y-619378D02*
X51197Y-620113D01*
X51823Y-620533D01*
X52528Y-620638D01*
X53155Y-620533D01*
X53782Y-620008D01*
X54173Y-619378D01*
X54252Y-618748D01*
X54095Y-618013D01*
X53547Y-617488D01*
X52998Y-617278D01*
X52293D01*
G01X52998D02*
X53468Y-616963D01*
X53860Y-616438D01*
X54017Y-615808D01*
X53860Y-615178D01*
X53468Y-614653D01*
X52763Y-614338D01*
X52058Y-614443D01*
X51353Y-614863D01*
G01X58593Y-620638D02*
X58750Y-619273D01*
X58985Y-618118D01*
X59298Y-617068D01*
X59690Y-615913D01*
X60317Y-614338D01*
X57183D01*
G01X64893Y-620638D02*
X65050Y-619273D01*
X65285Y-618118D01*
X65598Y-617068D01*
X65990Y-615913D01*
X66617Y-614338D01*
X63483D01*
G01X71193Y-621793D02*
X71507Y-620428D01*
G01X77650Y-614338D02*
Y-620638D01*
G01X75848Y-614338D02*
X79452D01*
G01X81992Y-620638D02*
X83950Y-614338D01*
X85908Y-620638D01*
G01X85203Y-618433D02*
X82697D01*
G01X89310Y-614338D02*
X91190D01*
G01X90250D02*
Y-620638D01*
G01X89310D02*
X91190D01*
G01X94200Y-614338D02*
X95297Y-620638D01*
X96550Y-614338D01*
X97803Y-620638D01*
X98900Y-614338D01*
G01X100892Y-620638D02*
X102850Y-614338D01*
X104808Y-620638D01*
G01X104103Y-618433D02*
X101597D01*
G01X107348Y-620638D02*
Y-614338D01*
X110952Y-620638D01*
Y-614338D01*
G01X121358Y-622738D02*
X120575Y-621688D01*
X120183Y-620638D01*
Y-616438D01*
X120575Y-615388D01*
X121358Y-614338D01*
G01X132783Y-620638D02*
Y-614338D01*
X134742D01*
X135368Y-614653D01*
X135760Y-615073D01*
X135917Y-615913D01*
X135760Y-616753D01*
X135290Y-617278D01*
X134742Y-617593D01*
X132783D01*
G01X134742D02*
X135917Y-620638D01*
G01X140650Y-620848D02*
X140493Y-620743D01*
Y-620533D01*
X140650Y-620428D01*
X140807Y-620533D01*
Y-620743D01*
X140650Y-620848D01*
G01X146950Y-620638D02*
X146323Y-620533D01*
X145775Y-620113D01*
X145305Y-619483D01*
X144992Y-618748D01*
X144835Y-617908D01*
Y-617068D01*
X144992Y-616228D01*
X145305Y-615493D01*
X145775Y-614863D01*
X146323Y-614443D01*
X146950Y-614338D01*
X147577Y-614443D01*
X148125Y-614863D01*
X148595Y-615493D01*
X148908Y-616228D01*
X149065Y-617068D01*
Y-617908D01*
X148908Y-618748D01*
X148595Y-619483D01*
X148125Y-620113D01*
X147577Y-620533D01*
X146950Y-620638D01*
G01X153250Y-620848D02*
X153093Y-620743D01*
Y-620533D01*
X153250Y-620428D01*
X153407Y-620533D01*
Y-620743D01*
X153250Y-620848D01*
G01X161273Y-614863D02*
X160803Y-614548D01*
X160255Y-614338D01*
X159628D01*
X158923Y-614653D01*
X158375Y-615178D01*
X157983Y-615808D01*
X157670Y-616858D01*
X157592Y-617803D01*
X157748Y-618748D01*
X157983Y-619378D01*
X158453Y-620008D01*
X159002Y-620428D01*
X159550Y-620638D01*
X160098D01*
X160647Y-620428D01*
X161117Y-620113D01*
X161508Y-619693D01*
G01X165850Y-620848D02*
X165693Y-620743D01*
Y-620533D01*
X165850Y-620428D01*
X166007Y-620533D01*
Y-620743D01*
X165850Y-620848D01*
G01X172542Y-622738D02*
X173325Y-621688D01*
X173717Y-620638D01*
Y-616438D01*
X173325Y-615388D01*
X172542Y-614338D01*
G01X6548Y-600638D02*
Y-594338D01*
X10152Y-600638D01*
Y-594338D01*
G01X14650Y-600638D02*
X14023Y-600533D01*
X13475Y-600113D01*
X13005Y-599483D01*
X12692Y-598748D01*
X12535Y-597908D01*
Y-597068D01*
X12692Y-596228D01*
X13005Y-595493D01*
X13475Y-594863D01*
X14023Y-594443D01*
X14650Y-594338D01*
X15277Y-594443D01*
X15825Y-594863D01*
X16295Y-595493D01*
X16608Y-596228D01*
X16765Y-597068D01*
Y-597908D01*
X16608Y-598748D01*
X16295Y-599483D01*
X15825Y-600113D01*
X15277Y-600533D01*
X14650Y-600638D01*
G01X20950Y-600848D02*
X20793Y-600743D01*
Y-600533D01*
X20950Y-600428D01*
X21107Y-600533D01*
Y-600743D01*
X20950Y-600848D01*
G01X25762Y-595388D02*
X26232Y-594758D01*
X26780Y-594443D01*
X27407Y-594338D01*
X28190Y-594548D01*
X28738Y-595073D01*
X28895Y-595703D01*
X28817Y-596333D01*
X28503Y-596858D01*
X26937Y-597908D01*
X26232Y-598643D01*
X25762Y-599693D01*
X25605Y-600638D01*
X28895D01*
G01X33550D02*
Y-594338D01*
X32610Y-595598D01*
G01Y-600638D02*
X34490D01*
G01X39850D02*
Y-594338D01*
X38910Y-595598D01*
G01Y-600638D02*
X40790D01*
G01X45993Y-601793D02*
X46307Y-600428D01*
G01X50100Y-594338D02*
X51197Y-600638D01*
X52450Y-594338D01*
X53703Y-600638D01*
X54800Y-594338D01*
G01X60317Y-600638D02*
X57183D01*
Y-594338D01*
X60317D01*
G01X59063Y-597383D02*
X57183D01*
G01X63248Y-600638D02*
Y-594338D01*
X66852Y-600638D01*
Y-594338D01*
G01X69705Y-600638D02*
Y-594338D01*
G01X72995D02*
Y-600638D01*
G01Y-597488D02*
X69705D01*
G01X75927Y-594338D02*
Y-598853D01*
X76240Y-599798D01*
X76867Y-600428D01*
X77650Y-600638D01*
X78433Y-600428D01*
X79060Y-599798D01*
X79373Y-598853D01*
Y-594338D01*
G01X81992Y-600638D02*
X83950Y-594338D01*
X85908Y-600638D01*
G01X85203Y-598433D02*
X82697D01*
G01X95062Y-595388D02*
X95532Y-594758D01*
X96080Y-594443D01*
X96707Y-594338D01*
X97490Y-594548D01*
X98038Y-595073D01*
X98195Y-595703D01*
X98117Y-596333D01*
X97803Y-596858D01*
X96237Y-597908D01*
X95532Y-598643D01*
X95062Y-599693D01*
X94905Y-600638D01*
X98195D01*
G01X101048D02*
Y-594338D01*
X104652Y-600638D01*
Y-594338D01*
G01X107427Y-600638D02*
Y-594338D01*
X108993D01*
X109620Y-594653D01*
X110090Y-595073D01*
X110482Y-595703D01*
X110795Y-596438D01*
X110873Y-597488D01*
X110795Y-598538D01*
X110482Y-599273D01*
X110090Y-599903D01*
X109620Y-600323D01*
X108993Y-600638D01*
X107427D01*
G01X120183D02*
Y-594338D01*
X122142D01*
X122768Y-594653D01*
X123160Y-595073D01*
X123317Y-595913D01*
X123160Y-596753D01*
X122690Y-597278D01*
X122142Y-597593D01*
X120183D01*
G01X122142D02*
X123317Y-600638D01*
G01X126327D02*
Y-594338D01*
X127893D01*
X128520Y-594653D01*
X128990Y-595073D01*
X129382Y-595703D01*
X129695Y-596438D01*
X129773Y-597488D01*
X129695Y-598538D01*
X129382Y-599273D01*
X128990Y-599903D01*
X128520Y-600323D01*
X127893Y-600638D01*
X126327D01*
G01X134350Y-600848D02*
X134193Y-600743D01*
Y-600533D01*
X134350Y-600428D01*
X134507Y-600533D01*
Y-600743D01*
X134350Y-600848D01*
G01X30650Y-589938D02*
X28130Y-589521D01*
X25925Y-587855D01*
X24035Y-585355D01*
X22775Y-582438D01*
X22145Y-579105D01*
Y-575771D01*
X22775Y-572438D01*
X24035Y-569521D01*
X25925Y-567022D01*
X28130Y-565355D01*
X30650Y-564938D01*
X33170Y-565355D01*
X35375Y-567022D01*
X37265Y-569521D01*
X38525Y-572438D01*
X39155Y-575771D01*
Y-579105D01*
X38525Y-582438D01*
X37265Y-585355D01*
X35375Y-587855D01*
X33170Y-589521D01*
X30650Y-589938D01*
G01X33170Y-583271D02*
X36950Y-589938D01*
G01X50495Y-573272D02*
Y-584938D01*
X51755Y-587855D01*
X53645Y-589521D01*
X55850Y-589938D01*
X58055Y-589521D01*
X59945Y-587855D01*
X61205Y-584938D01*
G01Y-589938D02*
Y-573272D01*
G01X86720Y-589938D02*
Y-573272D01*
G01Y-576188D02*
X85460Y-574522D01*
X83570Y-573688D01*
X81365Y-573272D01*
X79160Y-574105D01*
X77270Y-575771D01*
X76010Y-578272D01*
X75380Y-581605D01*
X76010Y-584938D01*
X77270Y-587439D01*
X79160Y-589105D01*
X81365Y-589938D01*
X83570Y-589521D01*
X85460Y-588272D01*
X86720Y-586605D01*
G01X100895Y-589938D02*
Y-573272D01*
G01Y-577438D02*
X102155Y-575355D01*
X104045Y-573688D01*
X106565Y-573272D01*
X108770Y-573688D01*
X110660Y-575355D01*
X111605Y-578272D01*
Y-589938D01*
G01X131450Y-564938D02*
Y-589938D01*
G01X127040Y-573272D02*
X135860D01*
G01X162320Y-589938D02*
Y-573272D01*
G01Y-576188D02*
X161060Y-574522D01*
X159170Y-573688D01*
X156965Y-573272D01*
X154760Y-574105D01*
X152870Y-575771D01*
X151610Y-578272D01*
X150980Y-581605D01*
X151610Y-584938D01*
X152870Y-587439D01*
X154760Y-589105D01*
X156965Y-589938D01*
X159170Y-589521D01*
X161060Y-588272D01*
X162320Y-586605D01*
G01X25935Y-29134D02*
G03I-6250J0D01*
G01Y1803261D02*
G03I-6250J0D01*
G01X53149Y-29134D02*
G03I-5905J0D01*
G01X202000Y-569638D02*
Y-577638D01*
X206000D01*
G01X213800D02*
Y-572305D01*
G01Y-573238D02*
X213400Y-572705D01*
X212800Y-572438D01*
X212100Y-572305D01*
X211400Y-572571D01*
X210800Y-573105D01*
X210400Y-573905D01*
X210200Y-574971D01*
X210400Y-576038D01*
X210800Y-576838D01*
X211400Y-577371D01*
X212100Y-577638D01*
X212800Y-577505D01*
X213400Y-577105D01*
X213800Y-576572D01*
G01X217900Y-580038D02*
X218500Y-580305D01*
X219300Y-580038D01*
X219800Y-579505D01*
X220200Y-578838D01*
X220800Y-576705D01*
X222100Y-572305D01*
G01X218900D02*
X220800Y-576705D01*
G01X226500Y-574038D02*
X229700D01*
X229400Y-573105D01*
X228900Y-572571D01*
X228200Y-572305D01*
X227500Y-572438D01*
X226900Y-572838D01*
X226500Y-573771D01*
X226300Y-574572D01*
Y-575371D01*
X226500Y-576171D01*
X227000Y-576971D01*
X227600Y-577505D01*
X228300Y-577638D01*
X229000Y-577371D01*
X229700Y-576572D01*
G01X234600Y-577638D02*
Y-572305D01*
G01Y-573371D02*
X235100Y-572838D01*
X235600Y-572438D01*
X236300Y-572305D01*
X236800Y-572438D01*
X237400Y-572838D01*
G01X226000Y-626038D02*
X226500Y-626838D01*
X227100Y-627371D01*
X227800Y-627638D01*
X228600Y-627371D01*
X229200Y-626838D01*
X229800Y-626038D01*
X230000Y-624971D01*
Y-619638D01*
G01X237800Y-627638D02*
Y-622305D01*
G01Y-623238D02*
X237400Y-622705D01*
X236800Y-622438D01*
X236100Y-622305D01*
X235400Y-622571D01*
X234800Y-623105D01*
X234400Y-623905D01*
X234200Y-624971D01*
X234400Y-626038D01*
X234800Y-626838D01*
X235400Y-627371D01*
X236100Y-627638D01*
X236800Y-627505D01*
X237400Y-627105D01*
X237800Y-626572D01*
G01X245600Y-622971D02*
X244900Y-622438D01*
X244300Y-622305D01*
X243500Y-622571D01*
X242900Y-623105D01*
X242500Y-624038D01*
X242400Y-624971D01*
X242500Y-625905D01*
X242900Y-626705D01*
X243500Y-627371D01*
X244300Y-627638D01*
X245000Y-627371D01*
X245600Y-626838D01*
G01X250300Y-627638D02*
Y-619638D01*
G01X253500Y-622305D02*
X250300Y-625371D01*
G01X251600Y-624171D02*
X253700Y-627638D01*
G01X221000Y-602638D02*
Y-594638D01*
X223400D01*
X224200Y-595038D01*
X224800Y-595971D01*
X225000Y-597038D01*
X224800Y-598105D01*
X224300Y-598905D01*
X223400Y-599305D01*
X221000D01*
G01X228500Y-602638D02*
X231000Y-594638D01*
X233500Y-602638D01*
G01X232600Y-599838D02*
X229400D01*
G01X236700Y-602638D02*
Y-594638D01*
X241300Y-602638D01*
Y-594638D01*
G01X249000Y-602638D02*
X245000D01*
Y-594638D01*
X249000D01*
G01X247400Y-598505D02*
X245000D01*
G01X253000Y-594638D02*
Y-602638D01*
X257000D01*
G01X328600Y-620971D02*
X329200Y-620171D01*
X329900Y-619771D01*
X330700Y-619638D01*
X331700Y-619905D01*
X332400Y-620571D01*
X332600Y-621371D01*
X332500Y-622172D01*
X332100Y-622838D01*
X330100Y-624171D01*
X329200Y-625105D01*
X328600Y-626438D01*
X328400Y-627638D01*
X332600D01*
G01X338500Y-619638D02*
X337700Y-619905D01*
X337100Y-620571D01*
X336700Y-621371D01*
X336400Y-622438D01*
X336300Y-623638D01*
X336400Y-624838D01*
X336700Y-625905D01*
X337100Y-626705D01*
X337700Y-627371D01*
X338500Y-627638D01*
X339300Y-627371D01*
X339900Y-626705D01*
X340300Y-625905D01*
X340600Y-624838D01*
X340700Y-623638D01*
X340600Y-622438D01*
X340300Y-621371D01*
X339900Y-620571D01*
X339300Y-619905D01*
X338500Y-619638D01*
G01X344600Y-620971D02*
X345200Y-620171D01*
X345900Y-619771D01*
X346700Y-619638D01*
X347700Y-619905D01*
X348400Y-620571D01*
X348600Y-621371D01*
X348500Y-622172D01*
X348100Y-622838D01*
X346100Y-624171D01*
X345200Y-625105D01*
X344600Y-626438D01*
X344400Y-627638D01*
X348600D01*
G01X352300Y-626038D02*
X352900Y-626971D01*
X353700Y-627505D01*
X354600Y-627638D01*
X355400Y-627505D01*
X356200Y-626838D01*
X356700Y-626038D01*
X356800Y-625238D01*
X356600Y-624305D01*
X355900Y-623638D01*
X355200Y-623371D01*
X354300D01*
G01X355200D02*
X355800Y-622971D01*
X356300Y-622305D01*
X356500Y-621505D01*
X356300Y-620705D01*
X355800Y-620038D01*
X354900Y-619638D01*
X354000Y-619771D01*
X353100Y-620305D01*
G01X360700Y-627905D02*
X364300Y-619638D01*
G01X370500D02*
X369700Y-619905D01*
X369100Y-620571D01*
X368700Y-621371D01*
X368400Y-622438D01*
X368300Y-623638D01*
X368400Y-624838D01*
X368700Y-625905D01*
X369100Y-626705D01*
X369700Y-627371D01*
X370500Y-627638D01*
X371300Y-627371D01*
X371900Y-626705D01*
X372300Y-625905D01*
X372600Y-624838D01*
X372700Y-623638D01*
X372600Y-622438D01*
X372300Y-621371D01*
X371900Y-620571D01*
X371300Y-619905D01*
X370500Y-619638D01*
G01X379700Y-627638D02*
Y-619638D01*
X376000Y-625371D01*
X381000D01*
G01X384700Y-627905D02*
X388300Y-619638D01*
G01X394500Y-627638D02*
Y-619638D01*
X393300Y-621238D01*
G01Y-627638D02*
X395700D01*
G01X402300D02*
X402500Y-625905D01*
X402800Y-624438D01*
X403200Y-623105D01*
X403700Y-621638D01*
X404500Y-619638D01*
X400500D01*
G01X328300Y-602638D02*
Y-594638D01*
X330300D01*
X331100Y-595038D01*
X331700Y-595571D01*
X332200Y-596371D01*
X332600Y-597305D01*
X332700Y-598638D01*
X332600Y-599971D01*
X332200Y-600905D01*
X331700Y-601705D01*
X331100Y-602238D01*
X330300Y-602638D01*
X328300D01*
G01X336000D02*
X338500Y-594638D01*
X341000Y-602638D01*
G01X340100Y-599838D02*
X336900D01*
G01X344600Y-602638D02*
Y-594638D01*
X348400D01*
G01X347000Y-598505D02*
X344600D01*
G01X354500Y-594638D02*
X353700Y-594905D01*
X353100Y-595571D01*
X352700Y-596371D01*
X352400Y-597438D01*
X352300Y-598638D01*
X352400Y-599838D01*
X352700Y-600905D01*
X353100Y-601705D01*
X353700Y-602371D01*
X354500Y-602638D01*
X355300Y-602371D01*
X355900Y-601705D01*
X356300Y-600905D01*
X356600Y-599838D01*
X356700Y-598638D01*
X356600Y-597438D01*
X356300Y-596371D01*
X355900Y-595571D01*
X355300Y-594905D01*
X354500Y-594638D01*
G01X362500D02*
Y-602638D01*
G01X360200Y-594638D02*
X364800D01*
G01X367900Y-602638D02*
Y-594638D01*
X370500Y-601305D01*
X373100Y-594638D01*
Y-602638D01*
G01X379300Y-598371D02*
X379700Y-597971D01*
X380000Y-597305D01*
X380200Y-596371D01*
X380000Y-595571D01*
X379600Y-595038D01*
X378900Y-594638D01*
X376200D01*
Y-602638D01*
X379500D01*
X380200Y-602105D01*
X380600Y-601305D01*
X380800Y-600371D01*
X380600Y-599438D01*
X380000Y-598638D01*
X379300Y-598371D01*
X376200D01*
G01X384300Y-601038D02*
X384900Y-601971D01*
X385700Y-602505D01*
X386600Y-602638D01*
X387400Y-602505D01*
X388200Y-601838D01*
X388700Y-601038D01*
X388800Y-600238D01*
X388600Y-599305D01*
X387900Y-598638D01*
X387200Y-598371D01*
X386300D01*
G01X387200D02*
X387800Y-597971D01*
X388300Y-597305D01*
X388500Y-596505D01*
X388300Y-595705D01*
X387800Y-595038D01*
X386900Y-594638D01*
X386000Y-594771D01*
X385100Y-595305D01*
G01X393300Y-594638D02*
X395700D01*
G01X394500D02*
Y-602638D01*
G01X393300D02*
X395700D01*
G01X404700Y-595305D02*
X404100Y-594905D01*
X403400Y-594638D01*
X402600D01*
X401700Y-595038D01*
X401000Y-595705D01*
X400500Y-596505D01*
X400100Y-597838D01*
X400000Y-599038D01*
X400200Y-600238D01*
X400500Y-601038D01*
X401100Y-601838D01*
X401800Y-602371D01*
X402500Y-602638D01*
X403200D01*
X403900Y-602371D01*
X404500Y-601971D01*
X405000Y-601438D01*
G01X410500Y-594638D02*
X409700Y-594905D01*
X409100Y-595571D01*
X408700Y-596371D01*
X408400Y-597438D01*
X408300Y-598638D01*
X408400Y-599838D01*
X408700Y-600905D01*
X409100Y-601705D01*
X409700Y-602371D01*
X410500Y-602638D01*
X411300Y-602371D01*
X411900Y-601705D01*
X412300Y-600905D01*
X412600Y-599838D01*
X412700Y-598638D01*
X412600Y-597438D01*
X412300Y-596371D01*
X411900Y-595571D01*
X411300Y-594905D01*
X410500Y-594638D01*
G01X346100Y-577638D02*
Y-569638D01*
X349900D01*
G01X348500Y-573505D02*
X346100D01*
G01X356000Y-569638D02*
X355200Y-569905D01*
X354600Y-570571D01*
X354200Y-571371D01*
X353900Y-572438D01*
X353800Y-573638D01*
X353900Y-574838D01*
X354200Y-575905D01*
X354600Y-576705D01*
X355200Y-577371D01*
X356000Y-577638D01*
X356800Y-577371D01*
X357400Y-576705D01*
X357800Y-575905D01*
X358100Y-574838D01*
X358200Y-573638D01*
X358100Y-572438D01*
X357800Y-571371D01*
X357400Y-570571D01*
X356800Y-569905D01*
X356000Y-569638D01*
G01X364000D02*
Y-577638D01*
G01X361700Y-569638D02*
X366300D01*
G01X372600Y-573638D02*
X374600D01*
Y-576038D01*
X374000Y-576838D01*
X373300Y-577371D01*
X372300Y-577638D01*
X371300Y-577371D01*
X370600Y-576838D01*
X370000Y-576038D01*
X369600Y-575105D01*
X369400Y-574038D01*
Y-573105D01*
X369600Y-572305D01*
X370000Y-571371D01*
X370600Y-570571D01*
X371200Y-570038D01*
X372000Y-569638D01*
X372700D01*
X373500Y-569905D01*
X374100Y-570438D01*
G01X377000Y-580305D02*
X383000D01*
G01X385400Y-577638D02*
Y-569638D01*
X388000Y-576305D01*
X390600Y-569638D01*
Y-577638D01*
G01X396800Y-573371D02*
X397200Y-572971D01*
X397500Y-572305D01*
X397700Y-571371D01*
X397500Y-570571D01*
X397100Y-570038D01*
X396400Y-569638D01*
X393700D01*
Y-577638D01*
X397000D01*
X397700Y-577105D01*
X398100Y-576305D01*
X398300Y-575371D01*
X398100Y-574438D01*
X397500Y-573638D01*
X396800Y-573371D01*
X393700D01*
G01X417000Y-630638D02*
Y-622638D01*
X415800Y-624238D01*
G01Y-630638D02*
X418200D01*
G01X423100Y-627305D02*
X423800Y-626371D01*
X424400Y-625838D01*
X425200Y-625571D01*
X425900Y-625838D01*
X426400Y-626371D01*
X426800Y-627171D01*
X426900Y-628105D01*
X426800Y-628905D01*
X426400Y-629705D01*
X425800Y-630371D01*
X425100Y-630638D01*
X424300Y-630371D01*
X423600Y-629572D01*
X423200Y-628371D01*
X423100Y-627038D01*
X423300Y-625305D01*
X423600Y-624371D01*
X424100Y-623438D01*
X424800Y-622771D01*
X425500Y-622638D01*
X426200Y-622905D01*
X426700Y-623571D01*
G01X433000Y-630905D02*
X432800Y-630771D01*
Y-630505D01*
X433000Y-630371D01*
X433200Y-630505D01*
Y-630771D01*
X433000Y-630905D01*
G01X439100Y-627305D02*
X439800Y-626371D01*
X440400Y-625838D01*
X441200Y-625571D01*
X441900Y-625838D01*
X442400Y-626371D01*
X442800Y-627171D01*
X442900Y-628105D01*
X442800Y-628905D01*
X442400Y-629705D01*
X441800Y-630371D01*
X441100Y-630638D01*
X440300Y-630371D01*
X439600Y-629572D01*
X439200Y-628371D01*
X439100Y-627038D01*
X439300Y-625305D01*
X439600Y-624371D01*
X440100Y-623438D01*
X440800Y-622771D01*
X441500Y-622638D01*
X442200Y-622905D01*
X442700Y-623571D01*
G01X462000Y-630638D02*
Y-622638D01*
X460800Y-624238D01*
G01Y-630638D02*
X463200D01*
G01X469800D02*
X470000Y-628905D01*
X470300Y-627438D01*
X470700Y-626105D01*
X471200Y-624638D01*
X472000Y-622638D01*
X468000D01*
G01X478000Y-630905D02*
X477800Y-630771D01*
Y-630505D01*
X478000Y-630371D01*
X478200Y-630505D01*
Y-630771D01*
X478000Y-630905D01*
G01X484100Y-623971D02*
X484700Y-623171D01*
X485400Y-622771D01*
X486200Y-622638D01*
X487200Y-622905D01*
X487900Y-623571D01*
X488100Y-624371D01*
X488000Y-625172D01*
X487600Y-625838D01*
X485600Y-627171D01*
X484700Y-628105D01*
X484100Y-629438D01*
X483900Y-630638D01*
X488100D01*
G01X486200Y-598305D02*
X485600Y-597905D01*
X484900Y-597638D01*
X484100D01*
X483200Y-598038D01*
X482500Y-598705D01*
X482000Y-599505D01*
X481600Y-600838D01*
X481500Y-602038D01*
X481700Y-603238D01*
X482000Y-604038D01*
X482600Y-604838D01*
X483300Y-605371D01*
X484000Y-605638D01*
X484700D01*
X485400Y-605371D01*
X486000Y-604971D01*
X486500Y-604438D01*
G01X1004442Y1879613D02*
X1005372Y1880862D01*
X1006457Y1881488D01*
X1007697Y1881696D01*
X1009247Y1881279D01*
X1010332Y1880238D01*
X1010642Y1878988D01*
X1010487Y1877737D01*
X1009867Y1876696D01*
X1006767Y1874613D01*
X1005372Y1873154D01*
X1004442Y1871071D01*
X1004132Y1869196D01*
X1010642D01*
G01X1019787D02*
Y1881696D01*
X1017927Y1879196D01*
G01Y1869196D02*
X1021647D01*
G01X1032187Y1881696D02*
X1030947Y1881279D01*
X1030017Y1880238D01*
X1029397Y1878988D01*
X1028932Y1877321D01*
X1028777Y1875446D01*
X1028932Y1873571D01*
X1029397Y1871904D01*
X1030017Y1870654D01*
X1030947Y1869613D01*
X1032187Y1869196D01*
X1033427Y1869613D01*
X1034357Y1870654D01*
X1034977Y1871904D01*
X1035442Y1873571D01*
X1035597Y1875446D01*
X1035442Y1877321D01*
X1034977Y1878988D01*
X1034357Y1880238D01*
X1033427Y1881279D01*
X1032187Y1881696D01*
G01X1044587Y1869196D02*
Y1881696D01*
X1042727Y1879196D01*
G01Y1869196D02*
X1046447D01*
G01X1053577Y1871071D02*
X1054507Y1870029D01*
X1055592Y1869404D01*
X1056987Y1869196D01*
X1058382Y1869613D01*
X1059467Y1870446D01*
X1060242Y1871904D01*
X1060397Y1873571D01*
X1060087Y1875238D01*
X1059312Y1876279D01*
X1058227Y1877113D01*
X1057142Y1877321D01*
X1056057Y1877113D01*
X1054662Y1876279D01*
X1055127Y1881696D01*
X1059312D01*
G01X1069387Y1868779D02*
X1069077Y1868988D01*
Y1869404D01*
X1069387Y1869613D01*
X1069697Y1869404D01*
Y1868988D01*
X1069387Y1868779D01*
G01X1081477Y1869196D02*
X1081787Y1871904D01*
X1082252Y1874196D01*
X1082872Y1876279D01*
X1083647Y1878571D01*
X1084887Y1881696D01*
X1078687D01*
G01X1096047Y1869196D02*
Y1881696D01*
X1090312Y1872738D01*
X1098062D01*
G01X1022727Y1846071D02*
X1023657Y1845029D01*
X1024742Y1844404D01*
X1026137Y1844196D01*
X1027532Y1844613D01*
X1028617Y1845446D01*
X1029392Y1846904D01*
X1029547Y1848571D01*
X1029237Y1850238D01*
X1028462Y1851279D01*
X1027377Y1852113D01*
X1026292Y1852321D01*
X1025207Y1852113D01*
X1023812Y1851279D01*
X1024277Y1856696D01*
X1028462D01*
G01X1035127Y1846696D02*
X1036057Y1845237D01*
X1037297Y1844404D01*
X1038692Y1844196D01*
X1039932Y1844404D01*
X1041172Y1845446D01*
X1041947Y1846696D01*
X1042102Y1847946D01*
X1041792Y1849404D01*
X1040707Y1850446D01*
X1039622Y1850863D01*
X1038227D01*
G01X1039622D02*
X1040552Y1851488D01*
X1041327Y1852529D01*
X1041637Y1853779D01*
X1041327Y1855029D01*
X1040552Y1856071D01*
X1039157Y1856696D01*
X1037762Y1856488D01*
X1036367Y1855654D01*
G01X1047527Y1846696D02*
X1048457Y1845237D01*
X1049697Y1844404D01*
X1051092Y1844196D01*
X1052332Y1844404D01*
X1053572Y1845446D01*
X1054347Y1846696D01*
X1054502Y1847946D01*
X1054192Y1849404D01*
X1053107Y1850446D01*
X1052022Y1850863D01*
X1050627D01*
G01X1052022D02*
X1052952Y1851488D01*
X1053727Y1852529D01*
X1054037Y1853779D01*
X1053727Y1855029D01*
X1052952Y1856071D01*
X1051557Y1856696D01*
X1050162Y1856488D01*
X1048767Y1855654D01*
G01X1063337Y1843779D02*
X1063027Y1843988D01*
Y1844404D01*
X1063337Y1844613D01*
X1063647Y1844404D01*
Y1843988D01*
X1063337Y1843779D01*
G01X1075737Y1844196D02*
X1076822Y1844404D01*
X1078062Y1845029D01*
X1078837Y1846071D01*
X1079147Y1847529D01*
X1078837Y1848987D01*
X1077907Y1850238D01*
X1076512Y1850863D01*
X1074962D01*
X1074032Y1851279D01*
X1073257Y1852321D01*
X1072947Y1853779D01*
X1073412Y1855238D01*
X1074497Y1856279D01*
X1075737Y1856696D01*
X1076977Y1856279D01*
X1078062Y1855238D01*
X1078527Y1853779D01*
X1078217Y1852321D01*
X1077442Y1851279D01*
X1076512Y1850863D01*
X1074962D01*
X1073567Y1850238D01*
X1072637Y1848987D01*
X1072327Y1847529D01*
X1072637Y1846071D01*
X1073412Y1845029D01*
X1074652Y1844404D01*
X1075737Y1844196D01*
G01X1844045Y18819D02*
G03I-6250J0D01*
G01Y1767677D02*
G03I-6250J0D01*
G01X1877510Y1291627D02*
G03I-6250J0D01*
G01X1891289Y49021D02*
G03I-6250J0D01*
G01X2040551Y1803261D02*
G03I-5906J0D01*
G01X2088139Y-29134D02*
G03I-6250J0D01*
G01Y1803261D02*
G03I-6250J0D01*
G01X2135324Y843664D02*
X2122824D01*
X2125324Y841804D01*
G01X2135324D02*
Y845524D01*
G01Y856064D02*
X2135116Y857149D01*
X2134491Y858389D01*
X2133449Y859164D01*
X2131991Y859474D01*
X2130533Y859164D01*
X2129282Y858234D01*
X2128657Y856839D01*
Y855289D01*
X2128241Y854359D01*
X2127199Y853584D01*
X2125741Y853274D01*
X2124282Y853739D01*
X2123241Y854824D01*
X2122824Y856064D01*
X2123241Y857304D01*
X2124282Y858389D01*
X2125741Y858854D01*
X2127199Y858544D01*
X2128241Y857769D01*
X2128657Y856839D01*
Y855289D01*
X2129282Y853894D01*
X2130533Y852964D01*
X2131991Y852654D01*
X2133449Y852964D01*
X2134491Y853739D01*
X2135116Y854979D01*
X2135324Y856064D01*
G01Y868154D02*
X2132616Y868464D01*
X2130324Y868929D01*
X2128241Y869549D01*
X2125949Y870324D01*
X2122824Y871564D01*
Y865364D01*
G01X2135324Y880864D02*
X2122824D01*
X2125324Y879004D01*
G01X2135324D02*
Y882724D01*
G01Y892954D02*
X2132616Y893264D01*
X2130324Y893729D01*
X2128241Y894349D01*
X2125949Y895124D01*
X2122824Y896364D01*
Y890164D01*
G01X2135741Y905664D02*
X2135532Y905354D01*
X2135116D01*
X2134907Y905664D01*
X2135116Y905974D01*
X2135532D01*
X2135741Y905664D01*
G01X2130116Y915119D02*
X2128657Y916204D01*
X2127824Y917134D01*
X2127407Y918374D01*
X2127824Y919459D01*
X2128657Y920234D01*
X2129907Y920854D01*
X2131366Y921009D01*
X2132616Y920854D01*
X2133866Y920234D01*
X2134907Y919304D01*
X2135324Y918219D01*
X2134907Y916979D01*
X2133658Y915894D01*
X2131782Y915274D01*
X2129699Y915119D01*
X2126991Y915429D01*
X2125532Y915894D01*
X2124074Y916669D01*
X2123032Y917754D01*
X2122824Y918839D01*
X2123241Y919924D01*
X2124282Y920699D01*
G01X2133449Y927054D02*
X2134491Y927984D01*
X2135116Y929069D01*
X2135324Y930464D01*
X2134907Y931859D01*
X2134074Y932944D01*
X2132616Y933719D01*
X2130949Y933874D01*
X2129282Y933564D01*
X2128241Y932789D01*
X2127407Y931704D01*
X2127199Y930619D01*
X2127407Y929534D01*
X2128241Y928139D01*
X2122824Y928604D01*
Y932789D01*
G01X2160324Y858074D02*
X2147824D01*
X2156782Y852339D01*
Y860089D01*
G01X2160324Y868304D02*
X2157616Y868614D01*
X2155324Y869079D01*
X2153241Y869699D01*
X2150949Y870474D01*
X2147824Y871714D01*
Y865514D01*
G01X2158449Y877604D02*
X2159491Y878534D01*
X2160116Y879619D01*
X2160324Y881014D01*
X2159907Y882409D01*
X2159074Y883494D01*
X2157616Y884269D01*
X2155949Y884424D01*
X2154282Y884114D01*
X2153241Y883339D01*
X2152407Y882254D01*
X2152199Y881169D01*
X2152407Y880084D01*
X2153241Y878689D01*
X2147824Y879154D01*
Y883339D01*
G01X2160741Y893414D02*
X2160532Y893104D01*
X2160116D01*
X2159907Y893414D01*
X2160116Y893724D01*
X2160532D01*
X2160741Y893414D01*
G01X2160324Y907674D02*
X2147824D01*
X2156782Y901939D01*
Y909689D01*
G01X2157824Y914804D02*
X2159283Y915734D01*
X2160116Y916974D01*
X2160324Y918369D01*
X2160116Y919609D01*
X2159074Y920849D01*
X2157824Y921624D01*
X2156574Y921779D01*
X2155116Y921469D01*
X2154074Y920384D01*
X2153657Y919299D01*
Y917904D01*
G01Y919299D02*
X2153032Y920229D01*
X2151991Y921004D01*
X2150741Y921314D01*
X2149491Y921004D01*
X2148449Y920229D01*
X2147824Y918834D01*
X2148032Y917439D01*
X2148866Y916044D01*
G01X2193700Y235196D02*
X2438109D01*
Y-48819D01*
X2193700D01*
Y235196D01*
G01X2240737Y182274D02*
G03I-6250J0D01*
G01X2240944Y83771D02*
G03I-5906J0D01*
G01X2249212Y10543D02*
X2258660D01*
G02Y2669I0J-3937D01*
G01X2249212D01*
G01X2278345Y10543D02*
G03Y2669I0J-3937D01*
G01X2287794D01*
G01X2278345Y10543D02*
X2287794D01*
M02*
